G04 ================== begin FILE IDENTIFICATION RECORD ==================*
G04 Layout Name:  9048_F0T_Management_Board_D_brd_V04_1213_1625.brd*
G04 Film Name:    gnd2*
G04 File Format:  Gerber RS274X*
G04 File Origin:  Cadence Allegro 17.2-S081*
G04 Origin Date:  Tue Dec 13 16:31:12 2022*
G04 *
G04 Layer:  DRAWING FORMAT/TITLE_BLOCK_A*
G04 Layer:  DRAWING FORMAT/TITLE_DATA_GND2*
G04 Layer:  ETCH/GND2*
G04 Layer:  PIN/GND2*
G04 Layer:  VIA CLASS/GND2*
G04 Layer:  MANUFACTURING/PHOTOPLOT_OUTLINE*
G04 Layer:  DRAWING FORMAT/TITLE_BLOCK*
G04 *
G04 Offset:    (0.00 0.00)*
G04 Mirror:    No*
G04 Mode:      Negative*
G04 Rotation:  0*
G04 FullContactRelief:  No*
G04 UndefLineWidth:     6.00*
G04 ================== end FILE IDENTIFICATION RECORD ====================*
%FSLAX25Y25*MOIN*%
%IR0*IPPOS*OFA0.00000B0.00000*MIA0B0*SFA1.00000B1.00000*%
%ADD19C,.03*%
%ADD25C,.052*%
%ADD23C,.061*%
%ADD39C,.071*%
%ADD28C,.026*%
%AMMACRO37*
4,1,36,.0025,0.0,
.002462,.000434,
.002349,.000855,
.002165,.00125,
.001915,.001607,
.001607,.001915,
.00125,.002165,
.000855,.002349,
.000434,.002462,
0.0,.0025,
-.000434,.002462,
-.000855,.002349,
-.00125,.002165,
-.001607,.001915,
-.001915,.001607,
-.002165,.00125,
-.002349,.000855,
-.002462,.000434,
-.0025,0.0,
-.002462,-.000434,
-.002349,-.000855,
-.002165,-.00125,
-.001915,-.001607,
-.001607,-.001915,
-.00125,-.002165,
-.000855,-.002349,
-.000434,-.002462,
0.0,-.0025,
.000434,-.002462,
.000855,-.002349,
.00125,-.002165,
.001607,-.001915,
.001915,-.001607,
.002165,-.00125,
.002349,-.000855,
.002462,-.000434,
.0025,0.0,
315.*
%
%ADD37MACRO37*%
%AMMACRO22*
4,1,36,.0025,0.0,
.002462,.000434,
.002349,.000855,
.002165,.00125,
.001915,.001607,
.001607,.001915,
.00125,.002165,
.000855,.002349,
.000434,.002462,
0.0,.0025,
-.000434,.002462,
-.000855,.002349,
-.00125,.002165,
-.001607,.001915,
-.001915,.001607,
-.002165,.00125,
-.002349,.000855,
-.002462,.000434,
-.0025,0.0,
-.002462,-.000434,
-.002349,-.000855,
-.002165,-.00125,
-.001915,-.001607,
-.001607,-.001915,
-.00125,-.002165,
-.000855,-.002349,
-.000434,-.002462,
0.0,-.0025,
.000434,-.002462,
.000855,-.002349,
.00125,-.002165,
.001607,-.001915,
.001915,-.001607,
.002165,-.00125,
.002349,-.000855,
.002462,-.000434,
.0025,0.0,
180.*
%
%ADD22MACRO22*%
%AMMACRO14*
4,1,36,.0025,0.0,
.002462,.000434,
.002349,.000855,
.002165,.00125,
.001915,.001607,
.001607,.001915,
.00125,.002165,
.000855,.002349,
.000434,.002462,
0.0,.0025,
-.000434,.002462,
-.000855,.002349,
-.00125,.002165,
-.001607,.001915,
-.001915,.001607,
-.002165,.00125,
-.002349,.000855,
-.002462,.000434,
-.0025,0.0,
-.002462,-.000434,
-.002349,-.000855,
-.002165,-.00125,
-.001915,-.001607,
-.001607,-.001915,
-.00125,-.002165,
-.000855,-.002349,
-.000434,-.002462,
0.0,-.0025,
.000434,-.002462,
.000855,-.002349,
.00125,-.002165,
.001607,-.001915,
.001915,-.001607,
.002165,-.00125,
.002349,-.000855,
.002462,-.000434,
.0025,0.0,
270.*
%
%ADD14MACRO14*%
%AMMACRO41*
4,1,36,.003,0.0,
.002954,.000521,
.002819,.001026,
.002598,.0015,
.002298,.001928,
.001928,.002298,
.0015,.002598,
.001026,.002819,
.000521,.002954,
0.0,.003,
-.000521,.002954,
-.001026,.002819,
-.0015,.002598,
-.001928,.002298,
-.002298,.001928,
-.002598,.0015,
-.002819,.001026,
-.002954,.000521,
-.003,0.0,
-.002954,-.000521,
-.002819,-.001026,
-.002598,-.0015,
-.002298,-.001928,
-.001928,-.002298,
-.0015,-.002598,
-.001026,-.002819,
-.000521,-.002954,
0.0,-.003,
.000521,-.002954,
.001026,-.002819,
.0015,-.002598,
.001928,-.002298,
.002298,-.001928,
.002598,-.0015,
.002819,-.001026,
.002954,-.000521,
.003,0.0,
270.*
%
%ADD41MACRO41*%
%AMMACRO44*
4,1,36,-.003,0.0,
-.002954,.000521,
-.002819,.001026,
-.002598,.0015,
-.002298,.001928,
-.001928,.002298,
-.0015,.002598,
-.001026,.002819,
-.000521,.002954,
0.0,.003,
.000521,.002954,
.001026,.002819,
.0015,.002598,
.001928,.002298,
.002298,.001928,
.002598,.0015,
.002819,.001026,
.002954,.000521,
.003,0.0,
.002954,-.000521,
.002819,-.001026,
.002598,-.0015,
.002298,-.001928,
.001928,-.002298,
.0015,-.002598,
.001026,-.002819,
.000521,-.002954,
0.0,-.003,
-.000521,-.002954,
-.001026,-.002819,
-.0015,-.002598,
-.001928,-.002298,
-.002298,-.001928,
-.002598,-.0015,
-.002819,-.001026,
-.002954,-.000521,
-.003,0.0,
270.*
%
%ADD44MACRO44*%
%ADD40C,.0435*%
%ADD32C,.048*%
%AMMACRO31*
4,1,16,.04562,.02794,
.049779,.019594,
.052425,.010652,
.053478,.001387,
.052906,-.007921,
.050727,-.016987,
.047007,-.025538,
.04562,-.02794,
.0507,-.03302,
.055664,-.023714,
.058936,-.013688,
.060417,-.003246,
.060063,.007295,
.057884,.017614,
.053946,.027397,
.0507,.03302,
.04562,.02794,
90.*
4,1,16,.02794,-.04562,
.019594,-.049779,
.010652,-.052425,
.001387,-.053478,
-.007921,-.052906,
-.016987,-.050727,
-.025538,-.047007,
-.02794,-.04562,
-.03302,-.0507,
-.023714,-.055664,
-.013688,-.058936,
-.003246,-.060417,
.007295,-.060063,
.017614,-.057884,
.027397,-.053946,
.03302,-.0507,
.02794,-.04562,
90.*
4,1,16,-.04562,-.02794,
-.049779,-.019594,
-.052425,-.010652,
-.053478,-.001387,
-.052906,.007921,
-.050727,.016987,
-.047007,.025538,
-.04562,.02794,
-.0507,.03302,
-.055664,.023714,
-.058936,.013688,
-.060417,.003246,
-.060063,-.007295,
-.057884,-.017614,
-.053946,-.027397,
-.0507,-.03302,
-.04562,-.02794,
90.*
4,1,16,-.02794,.04562,
-.019594,.049779,
-.010652,.052425,
-.001387,.053478,
.007921,.052906,
.016987,.050727,
.025538,.047007,
.02794,.04562,
.03302,.0507,
.023714,.055664,
.013688,.058936,
.003246,.060417,
-.007295,.060063,
-.017614,.057884,
-.027397,.053946,
-.03302,.0507,
-.02794,.04562,
90.*
%
%ADD31MACRO31*%
%ADD15C,.066*%
%AMMACRO18*
4,1,14,.06158,.03329,
.066425,.022091,
.069252,.010221,
.069975,-.00196,
.068571,-.014081,
.065084,-.025775,
.06158,-.03329,
.06672,-.03844,
.072381,-.02627,
.075844,-.013302,
.077001,.00007,
.075819,.01344,
.072334,.026402,
.06672,.03844,
.06158,.03329,
0.0*
4,1,14,.03329,-.06158,
.022091,-.066425,
.010221,-.069252,
-.00196,-.069975,
-.014081,-.068571,
-.025775,-.065084,
-.03329,-.06158,
-.03844,-.06672,
-.02627,-.072381,
-.013302,-.075844,
.00007,-.077001,
.01344,-.075819,
.026402,-.072334,
.03844,-.06672,
.03329,-.06158,
0.0*
4,1,14,-.06158,-.03329,
-.066425,-.022091,
-.069252,-.010221,
-.069975,.00196,
-.068571,.014081,
-.065084,.025775,
-.06158,.03329,
-.06672,.03844,
-.072381,.02627,
-.075844,.013302,
-.077001,-.00007,
-.075819,-.01344,
-.072334,-.026402,
-.06672,-.03844,
-.06158,-.03329,
0.0*
4,1,14,-.03329,.06158,
-.022091,.066425,
-.010221,.069252,
.00196,.069975,
.014081,.068571,
.025775,.065084,
.03329,.06158,
.03844,.06672,
.02627,.072381,
.013302,.075844,
-.00007,.077001,
-.01344,.075819,
-.026402,.072334,
-.03844,.06672,
-.03329,.06158,
0.0*
%
%ADD18MACRO18*%
%AMMACRO36*
4,1,15,.06525,.03697,
.070678,.025078,
.073959,.012424,
.074993,-.000608,
.073748,-.013621,
.070263,-.026221,
.06525,-.03697,
.07037,-.04209,
.07661,-.029231,
.080522,-.015484,
.081987,-.001266,
.080961,.01299,
.077476,.026852,
.071636,.039897,
.07037,.04209,
.06525,.03697,
0.0*
4,1,15,.03697,-.06525,
.025078,-.070678,
.012424,-.073959,
-.000608,-.074993,
-.013621,-.073748,
-.026221,-.070263,
-.03697,-.06525,
-.04209,-.07037,
-.029231,-.07661,
-.015484,-.080522,
-.001266,-.081987,
.01299,-.080961,
.026852,-.077476,
.039897,-.071636,
.04209,-.07037,
.03697,-.06525,
0.0*
4,1,15,-.06525,-.03697,
-.070678,-.025078,
-.073959,-.012424,
-.074993,.000608,
-.073748,.013621,
-.070263,.026221,
-.06525,.03697,
-.07037,.04209,
-.07661,.029231,
-.080522,.015484,
-.081987,.001266,
-.080961,-.01299,
-.077476,-.026852,
-.071636,-.039897,
-.07037,-.04209,
-.06525,-.03697,
0.0*
4,1,15,-.03697,.06525,
-.025078,.070678,
-.012424,.073959,
.000608,.074993,
.013621,.073748,
.026221,.070263,
.03697,.06525,
.04209,.07037,
.029231,.07661,
.015484,.080522,
.001266,.081987,
-.01299,.080961,
-.026852,.077476,
-.039897,.071636,
-.04209,.07037,
-.03697,.06525,
0.0*
%
%ADD36MACRO36*%
%ADD26C,.078*%
%ADD11C,.087*%
%ADD33C,.097*%
%AMMACRO17*
4,1,15,.06231,.03403,
.067273,.022693,
.070191,.010666,
.070977,-.001684,
.069606,-.013984,
.066121,-.025858,
.06231,-.03403,
.06745,-.03917,
.073227,-.026862,
.076779,-.013739,
.077998,-.000197,
.076848,.01335,
.073362,.026492,
.067647,.038828,
.06745,.03917,
.06231,.03403,
0.0*
4,1,15,.03403,-.06231,
.022693,-.067273,
.010666,-.070191,
-.001684,-.070977,
-.013984,-.069606,
-.025858,-.066121,
-.03403,-.06231,
-.03917,-.06745,
-.026862,-.073227,
-.013739,-.076779,
-.000197,-.077998,
.01335,-.076848,
.026492,-.073362,
.038828,-.067647,
.03917,-.06745,
.03403,-.06231,
0.0*
4,1,15,-.06231,-.03403,
-.067273,-.022693,
-.070191,-.010666,
-.070977,.001684,
-.069606,.013984,
-.066121,.025858,
-.06231,.03403,
-.06745,.03917,
-.073227,.026862,
-.076779,.013739,
-.077998,.000197,
-.076848,-.01335,
-.073362,-.026492,
-.067647,-.038828,
-.06745,-.03917,
-.06231,-.03403,
0.0*
4,1,15,-.03403,.06231,
-.022693,.067273,
-.010666,.070191,
.001684,.070977,
.013984,.069606,
.025858,.066121,
.03403,.06231,
.03917,.06745,
.026862,.073227,
.013739,.076779,
.000197,.077998,
-.01335,.076848,
-.026492,.073362,
-.038828,.067647,
-.03917,.06745,
-.03403,.06231,
0.0*
%
%ADD17MACRO17*%
%AMMACRO30*
4,1,16,.0711,.04282,
.077455,.029823,
.081457,.01592,
.082984,.001533,
.08199,-.0129,
.078504,-.026942,
.072633,-.040164,
.0711,-.04282,
.07619,-.04791,
.083352,-.033952,
.087981,-.018962,
.089937,-.003396,
.089161,.012273,
.085675,.027569,
.079586,.042027,
.07619,.04791,
.0711,.04282,
0.0*
4,1,16,.04282,-.0711,
.029823,-.077455,
.01592,-.081457,
.001533,-.082984,
-.0129,-.08199,
-.026942,-.078504,
-.040164,-.072633,
-.04282,-.0711,
-.04791,-.07619,
-.033952,-.083352,
-.018962,-.087981,
-.003396,-.089937,
.012273,-.089161,
.027569,-.085675,
.042027,-.079586,
.04791,-.07619,
.04282,-.0711,
0.0*
4,1,16,-.0711,-.04282,
-.077455,-.029823,
-.081457,-.01592,
-.082984,-.001533,
-.08199,.0129,
-.078504,.026942,
-.072633,.040164,
-.0711,.04282,
-.07619,.04791,
-.083352,.033952,
-.087981,.018962,
-.089937,.003396,
-.089161,-.012273,
-.085675,-.027569,
-.079586,-.042027,
-.07619,-.04791,
-.0711,-.04282,
0.0*
4,1,16,-.04282,.0711,
-.029823,.077455,
-.01592,.081457,
-.001533,.082984,
.0129,.08199,
.026942,.078504,
.040164,.072633,
.04282,.0711,
.04791,.07619,
.033952,.083352,
.018962,.087981,
.003396,.089937,
-.012273,.089161,
-.027569,.085675,
-.042027,.079586,
-.04791,.07619,
-.04282,.0711,
0.0*
%
%ADD30MACRO30*%
%AMMACRO35*
4,1,15,.02142,.01082,
.022973,.006936,
.023829,.002841,
.02396,-.00134,
.023364,-.00548,
.022057,-.009454,
.02142,-.01082,
.02657,-.01597,
.02894,-.011114,
.03043,-.005919,
.030995,-.000545,
.030619,.004845,
.029313,.010088,
.027115,.015025,
.02657,.01597,
.02142,.01082,
0.0*
4,1,15,.01082,-.02142,
.006936,-.022973,
.002841,-.023829,
-.00134,-.02396,
-.00548,-.023364,
-.009454,-.022057,
-.01082,-.02142,
-.01597,-.02657,
-.011114,-.02894,
-.005919,-.03043,
-.000545,-.030995,
.004845,-.030619,
.010088,-.029313,
.015025,-.027115,
.01597,-.02657,
.01082,-.02142,
0.0*
4,1,15,-.02142,-.01082,
-.022973,-.006936,
-.023829,-.002841,
-.02396,.00134,
-.023364,.00548,
-.022057,.009454,
-.02142,.01082,
-.02657,.01597,
-.02894,.011114,
-.03043,.005919,
-.030995,.000545,
-.030619,-.004845,
-.029313,-.010088,
-.027115,-.015025,
-.02657,-.01597,
-.02142,-.01082,
0.0*
4,1,15,-.01082,.02142,
-.006936,.022973,
-.002841,.023829,
.00134,.02396,
.00548,.023364,
.009454,.022057,
.01082,.02142,
.01597,.02657,
.011114,.02894,
.005919,.03043,
.000545,.030995,
-.004845,.030619,
-.010088,.029313,
-.015025,.027115,
-.01597,.02657,
-.01082,.02142,
0.0*
%
%ADD35MACRO35*%
%AMMACRO34*
4,1,15,.01993,.00932,
.021246,.005718,
.021916,.001941,
.02192,-.001894,
.021258,-.005671,
.01995,-.009276,
.01993,-.00932,
.02511,-.01451,
.027248,-.009929,
.028558,-.005047,
.029001,-.000011,
.028562,.005025,
.027256,.009909,
.025121,.014491,
.02511,.01451,
.01993,.00932,
90.*
4,1,15,.00932,-.01993,
.005718,-.021246,
.001941,-.021916,
-.001894,-.02192,
-.005671,-.021258,
-.009276,-.01995,
-.00932,-.01993,
-.01451,-.02511,
-.009929,-.027248,
-.005047,-.028558,
-.000011,-.029001,
.005025,-.028562,
.009909,-.027256,
.014491,-.025121,
.01451,-.02511,
.00932,-.01993,
90.*
4,1,15,-.01993,-.00932,
-.021246,-.005718,
-.021916,-.001941,
-.02192,.001894,
-.021258,.005671,
-.01995,.009276,
-.01993,.00932,
-.02511,.01451,
-.027248,.009929,
-.028558,.005047,
-.029001,.000011,
-.028562,-.005025,
-.027256,-.009909,
-.025121,-.014491,
-.02511,-.01451,
-.01993,-.00932,
90.*
4,1,15,-.00932,.01993,
-.005718,.021246,
-.001941,.021916,
.001894,.02192,
.005671,.021258,
.009276,.01995,
.00932,.01993,
.01451,.02511,
.009929,.027248,
.005047,.028558,
.000011,.029001,
-.005025,.028562,
-.009909,.027256,
-.014491,.025121,
-.01451,.02511,
-.00932,.01993,
90.*
%
%ADD34MACRO34*%
%AMMACRO24*
4,1,15,.02475,.01414,
.026829,.009627,
.028094,.004822,
.028504,-.000129,
.028049,-.005077,
.026741,-.009871,
.02475,-.01414,
.02984,-.01923,
.032726,-.013756,
.034617,-.007864,
.035457,-.001734,
.03522,.00445,
.033912,.010498,
.031574,.016227,
.02984,.01923,
.02475,.01414,
0.0*
4,1,15,.01414,-.02475,
.009627,-.026829,
.004822,-.028094,
-.000129,-.028504,
-.005077,-.028049,
-.009871,-.026741,
-.01414,-.02475,
-.01923,-.02984,
-.013756,-.032726,
-.007864,-.034617,
-.001734,-.035457,
.00445,-.03522,
.010498,-.033912,
.016227,-.031574,
.01923,-.02984,
.01414,-.02475,
0.0*
4,1,15,-.02475,-.01414,
-.026829,-.009627,
-.028094,-.004822,
-.028504,.000129,
-.028049,.005077,
-.026741,.009871,
-.02475,.01414,
-.02984,.01923,
-.032726,.013756,
-.034617,.007864,
-.035457,.001734,
-.03522,-.00445,
-.033912,-.010498,
-.031574,-.016227,
-.02984,-.01923,
-.02475,-.01414,
0.0*
4,1,15,-.01414,.02475,
-.009627,.026829,
-.004822,.028094,
.000129,.028504,
.005077,.028049,
.009871,.026741,
.01414,.02475,
.01923,.02984,
.013756,.032726,
.007864,.034617,
.001734,.035457,
-.00445,.03522,
-.010498,.033912,
-.016227,.031574,
-.01923,.02984,
-.01414,.02475,
0.0*
%
%ADD24MACRO24*%
%AMMACRO10*
4,1,15,.03682,.01914,
.039584,.012455,
.041146,.005393,
.041457,-.001834,
.040509,-.009005,
.03833,-.015903,
.03682,-.01914,
.04197,-.0243,
.045552,-.016643,
.04775,-.00848,
.048497,-.000059,
.047771,.008363,
.045593,.016531,
.042029,.024197,
.04197,.0243,
.03682,.01914,
0.0*
4,1,15,.01914,-.03682,
.012455,-.039584,
.005393,-.041146,
-.001834,-.041457,
-.009005,-.040509,
-.015903,-.03833,
-.01914,-.03682,
-.0243,-.04197,
-.016643,-.045552,
-.00848,-.04775,
-.000059,-.048497,
.008363,-.047771,
.016531,-.045593,
.024197,-.042029,
.0243,-.04197,
.01914,-.03682,
0.0*
4,1,15,-.03682,-.01914,
-.039584,-.012455,
-.041146,-.005393,
-.041457,.001834,
-.040509,.009005,
-.03833,.015903,
-.03682,.01914,
-.04197,.0243,
-.045552,.016643,
-.04775,.00848,
-.048497,.000059,
-.047771,-.008363,
-.045593,-.016531,
-.042029,-.024197,
-.04197,-.0243,
-.03682,-.01914,
0.0*
4,1,15,-.01914,.03682,
-.012455,.039584,
-.005393,.041146,
.001834,.041457,
.009005,.040509,
.015903,.03833,
.01914,.03682,
.0243,.04197,
.016643,.045552,
.00848,.04775,
.000059,.048497,
-.008363,.047771,
-.016531,.045593,
-.024197,.042029,
-.0243,.04197,
-.01914,.03682,
0.0*
%
%ADD10MACRO10*%
%ADD29O,.156X.219*%
%ADD21C,.155*%
%AMMACRO38*
4,1,36,.0025,0.0,
.002462,.000434,
.002349,.000855,
.002165,.00125,
.001915,.001607,
.001607,.001915,
.00125,.002165,
.000855,.002349,
.000434,.002462,
0.0,.0025,
-.000434,.002462,
-.000855,.002349,
-.00125,.002165,
-.001607,.001915,
-.001915,.001607,
-.002165,.00125,
-.002349,.000855,
-.002462,.000434,
-.0025,0.0,
-.002462,-.000434,
-.002349,-.000855,
-.002165,-.00125,
-.001915,-.001607,
-.001607,-.001915,
-.00125,-.002165,
-.000855,-.002349,
-.000434,-.002462,
0.0,-.0025,
.000434,-.002462,
.000855,-.002349,
.00125,-.002165,
.001607,-.001915,
.001915,-.001607,
.002165,-.00125,
.002349,-.000855,
.002462,-.000434,
.0025,0.0,
45.*
%
%ADD38MACRO38*%
%AMMACRO20*
4,1,36,.0025,0.0,
.002462,.000434,
.002349,.000855,
.002165,.00125,
.001915,.001607,
.001607,.001915,
.00125,.002165,
.000855,.002349,
.000434,.002462,
0.0,.0025,
-.000434,.002462,
-.000855,.002349,
-.00125,.002165,
-.001607,.001915,
-.001915,.001607,
-.002165,.00125,
-.002349,.000855,
-.002462,.000434,
-.0025,0.0,
-.002462,-.000434,
-.002349,-.000855,
-.002165,-.00125,
-.001915,-.001607,
-.001607,-.001915,
-.00125,-.002165,
-.000855,-.002349,
-.000434,-.002462,
0.0,-.0025,
.000434,-.002462,
.000855,-.002349,
.00125,-.002165,
.001607,-.001915,
.001915,-.001607,
.002165,-.00125,
.002349,-.000855,
.002462,-.000434,
.0025,0.0,
90.*
%
%ADD20MACRO20*%
%AMMACRO42*
4,1,36,.003,0.0,
.002954,.000521,
.002819,.001026,
.002598,.0015,
.002298,.001928,
.001928,.002298,
.0015,.002598,
.001026,.002819,
.000521,.002954,
0.0,.003,
-.000521,.002954,
-.001026,.002819,
-.0015,.002598,
-.001928,.002298,
-.002298,.001928,
-.002598,.0015,
-.002819,.001026,
-.002954,.000521,
-.003,0.0,
-.002954,-.000521,
-.002819,-.001026,
-.002598,-.0015,
-.002298,-.001928,
-.001928,-.002298,
-.0015,-.002598,
-.001026,-.002819,
-.000521,-.002954,
0.0,-.003,
.000521,-.002954,
.001026,-.002819,
.0015,-.002598,
.001928,-.002298,
.002298,-.001928,
.002598,-.0015,
.002819,-.001026,
.002954,-.000521,
.003,0.0,
90.*
%
%ADD42MACRO42*%
%AMMACRO16*
4,1,36,.0025,0.0,
.002462,.000434,
.002349,.000855,
.002165,.00125,
.001915,.001607,
.001607,.001915,
.00125,.002165,
.000855,.002349,
.000434,.002462,
0.0,.0025,
-.000434,.002462,
-.000855,.002349,
-.00125,.002165,
-.001607,.001915,
-.001915,.001607,
-.002165,.00125,
-.002349,.000855,
-.002462,.000434,
-.0025,0.0,
-.002462,-.000434,
-.002349,-.000855,
-.002165,-.00125,
-.001915,-.001607,
-.001607,-.001915,
-.00125,-.002165,
-.000855,-.002349,
-.000434,-.002462,
0.0,-.0025,
.000434,-.002462,
.000855,-.002349,
.00125,-.002165,
.001607,-.001915,
.001915,-.001607,
.002165,-.00125,
.002349,-.000855,
.002462,-.000434,
.0025,0.0,
0.0*
%
%ADD16MACRO16*%
%AMMACRO43*
4,1,36,-.003,0.0,
-.002954,.000521,
-.002819,.001026,
-.002598,.0015,
-.002298,.001928,
-.001928,.002298,
-.0015,.002598,
-.001026,.002819,
-.000521,.002954,
0.0,.003,
.000521,.002954,
.001026,.002819,
.0015,.002598,
.001928,.002298,
.002298,.001928,
.002598,.0015,
.002819,.001026,
.002954,.000521,
.003,0.0,
.002954,-.000521,
.002819,-.001026,
.002598,-.0015,
.002298,-.001928,
.001928,-.002298,
.0015,-.002598,
.001026,-.002819,
.000521,-.002954,
0.0,-.003,
-.000521,-.002954,
-.001026,-.002819,
-.0015,-.002598,
-.001928,-.002298,
-.002298,-.001928,
-.002598,-.0015,
-.002819,-.001026,
-.002954,-.000521,
-.003,0.0,
90.*
%
%ADD43MACRO43*%
%AMMACRO27*
4,1,36,.0025,0.0,
.002462,.000434,
.002349,.000855,
.002165,.00125,
.001915,.001607,
.001607,.001915,
.00125,.002165,
.000855,.002349,
.000434,.002462,
0.0,.0025,
-.000434,.002462,
-.000855,.002349,
-.00125,.002165,
-.001607,.001915,
-.001915,.001607,
-.002165,.00125,
-.002349,.000855,
-.002462,.000434,
-.0025,0.0,
-.002462,-.000434,
-.002349,-.000855,
-.002165,-.00125,
-.001915,-.001607,
-.001607,-.001915,
-.00125,-.002165,
-.000855,-.002349,
-.000434,-.002462,
0.0,-.0025,
.000434,-.002462,
.000855,-.002349,
.00125,-.002165,
.001607,-.001915,
.001915,-.001607,
.002165,-.00125,
.002349,-.000855,
.002462,-.000434,
.0025,0.0,
84.*
%
%ADD27MACRO27*%
%AMMACRO13*
4,1,15,.03682,.01914,
.039584,.012455,
.041146,.005393,
.041457,-.001834,
.040509,-.009005,
.03833,-.015903,
.03682,-.01914,
.04197,-.0243,
.045552,-.016643,
.04775,-.00848,
.048497,-.000059,
.047771,.008363,
.045593,.016531,
.042029,.024197,
.04197,.0243,
.03682,.01914,
180.*
4,1,15,.01914,-.03682,
.012455,-.039584,
.005393,-.041146,
-.001834,-.041457,
-.009005,-.040509,
-.015903,-.03833,
-.01914,-.03682,
-.0243,-.04197,
-.016643,-.045552,
-.00848,-.04775,
-.000059,-.048497,
.008363,-.047771,
.016531,-.045593,
.024197,-.042029,
.0243,-.04197,
.01914,-.03682,
180.*
4,1,15,-.03682,-.01914,
-.039584,-.012455,
-.041146,-.005393,
-.041457,.001834,
-.040509,.009005,
-.03833,.015903,
-.03682,.01914,
-.04197,.0243,
-.045552,.016643,
-.04775,.00848,
-.048497,.000059,
-.047771,-.008363,
-.045593,-.016531,
-.042029,-.024197,
-.04197,-.0243,
-.03682,-.01914,
180.*
4,1,15,-.01914,.03682,
-.012455,.039584,
-.005393,.041146,
.001834,.041457,
.009005,.040509,
.015903,.03833,
.01914,.03682,
.0243,.04197,
.016643,.045552,
.00848,.04775,
.000059,.048497,
-.008363,.047771,
-.016531,.045593,
-.024197,.042029,
-.0243,.04197,
-.01914,.03682,
180.*
%
%ADD13MACRO13*%
%AMMACRO12*
4,1,15,-.03682,.01914,
-.039584,.012455,
-.041146,.005393,
-.041457,-.001834,
-.040509,-.009005,
-.03833,-.015903,
-.03682,-.01914,
-.04197,-.0243,
-.045552,-.016643,
-.04775,-.00848,
-.048497,-.000059,
-.047771,.008363,
-.045593,.016531,
-.042029,.024197,
-.04197,.0243,
-.03682,.01914,
180.*
4,1,15,-.01914,-.03682,
-.012455,-.039584,
-.005393,-.041146,
.001834,-.041457,
.009005,-.040509,
.015903,-.03833,
.01914,-.03682,
.0243,-.04197,
.016643,-.045552,
.00848,-.04775,
.000059,-.048497,
-.008363,-.047771,
-.016531,-.045593,
-.024197,-.042029,
-.0243,-.04197,
-.01914,-.03682,
180.*
4,1,15,.03682,-.01914,
.039584,-.012455,
.041146,-.005393,
.041457,.001834,
.040509,.009005,
.03833,.015903,
.03682,.01914,
.04197,.0243,
.045552,.016643,
.04775,.00848,
.048497,.000059,
.047771,-.008363,
.045593,-.016531,
.042029,-.024197,
.04197,-.0243,
.03682,-.01914,
180.*
4,1,15,.01914,.03682,
.012455,.039584,
.005393,.041146,
-.001834,.041457,
-.009005,.040509,
-.015903,.03833,
-.01914,.03682,
-.0243,.04197,
-.016643,.045552,
-.00848,.04775,
-.000059,.048497,
.008363,.047771,
.016531,.045593,
.024197,.042029,
.0243,.04197,
.01914,.03682,
180.*
%
%ADD12MACRO12*%
%ADD45C,.006*%
%ADD54C,.07306*%
%ADD51C,.08008*%
%ADD47C,.06807*%
%ADD53C,.06809*%
%ADD52C,.09908*%
%ADD49O,.03004X.06504*%
%ADD50O,.03006X.06506*%
%ADD46C,.16506*%
%ADD48O,.2363X.2993*%
G75*
%LPD*%
G75*
G36*
G01X-407000Y-793716D02*
X2010999D01*
Y1475775D01*
X-407000D01*
Y-793716D01*
G37*
%LPC*%
G75*
G36*
G01X-15748Y472016D02*
G02X-9874Y466142I0J-5874D01*
G01Y25945D01*
G02X-15748Y20071I-5874J0D01*
G01X-70000D01*
G02X-75874Y25945I0J5874D01*
G01Y466142D01*
G02X-70000Y472016I5874J0D01*
G01X-15748D01*
G37*
G36*
G01X2004Y336650D02*
Y442126D01*
G02X7874Y447996I5870J0D01*
G01X17717D01*
G03X21689Y451968I-1J3973D01*
G01Y467369D01*
X22132Y467812D01*
X23372D01*
X23781Y467404D01*
X38207D01*
X38828Y468024D01*
X40009D01*
X40378Y467655D01*
Y451968D01*
G03X44350Y447996I3973J1D01*
G01X50256D01*
G03X54228Y451968I-1J3973D01*
G01Y462100D01*
X122504D01*
Y451870D01*
G03X137339I7418J0D01*
G01Y462100D01*
X172543D01*
Y450098D01*
G03X183835I5646J0D01*
G01Y462100D01*
X252071D01*
Y450886D01*
G03X264937I6433J0D01*
G01Y462100D01*
X300122D01*
Y451968D01*
G03X304094Y447996I3973J1D01*
G01X310000D01*
G03X313973Y451969I0J3973D01*
G01Y467400D01*
X314385Y467812D01*
X315625D01*
X316034Y467404D01*
X330460D01*
X331081Y468024D01*
X332262D01*
X332642Y467644D01*
Y451968D01*
G03X336614Y447996I3973J1D01*
G01X346457D01*
G02X352327Y442126I0J-5870D01*
G01Y336650D01*
X345472D01*
G03X341500Y332678I0J-3973D01*
G01Y322834D01*
G03X345472Y318862I3972J0D01*
G01X352327D01*
Y271930D01*
X352331Y271926D01*
Y266763D01*
X352327Y266759D01*
Y7874D01*
G02X346457Y2004I-5870J0D01*
G01X7874D01*
G02X2004Y7874I0J5870D01*
G01Y242282D01*
X2000Y242286D01*
Y247986D01*
X2004Y247990D01*
Y318862D01*
X8858D01*
G03X12831Y322835I0J3973D01*
G01Y332677D01*
G03X8858Y336650I-3973J0D01*
G01X2004D01*
G37*
G36*
G01X364205Y466142D02*
G02X370079Y472016I5874J0D01*
G01X476378D01*
G02X482252Y466142I0J-5874D01*
G01Y-509842D01*
G02X476378Y-515716I-5874J0D01*
G01X370079D01*
G02X364205Y-509842I0J5874D01*
G01Y466142D01*
G37*
%LPD*%
G75*
G36*
G01X242870Y239000D02*
G02X243872Y238580I0J-1405D01*
G02Y236612I-853J-984D01*
G02X242870Y236192I-1002J985D01*
G02X242378Y236281I0J1404D01*
G01X242344Y236294D01*
X240395D01*
G02X239870Y236192I-525J1302D01*
G02Y239000I0J1404D01*
G02X240395Y238898I0J-1404D01*
G01X242344D01*
X242378Y238911D01*
G02X242870Y239000I492J-1315D01*
G37*
G36*
G01X239998Y225853D02*
Y229002D01*
G02X242602I1302J0D01*
G01Y226194D01*
G02X242638Y225890I-1264J-304D01*
G02X242261Y224974I-1301J0D01*
G02X241300Y224551I-961J880D01*
G02X239998Y225853I0J1302D01*
G37*
G36*
G01X250749Y236604D02*
X253898D01*
G02Y233998I0J-1303D01*
G01X250749D01*
G02Y236604I0J1303D01*
G37*
G36*
G01X253898Y233454D02*
X257047D01*
G02Y230848I0J-1303D01*
G01X253898D01*
G02Y233454I0J1303D01*
G37*
G36*
G01X153237Y61386D02*
X161111D01*
G02Y55780I0J-2803D01*
G01X153237D01*
G02Y61386I0J2803D01*
G37*
G36*
G01X165048Y55480D02*
X172922D01*
G02Y49874I0J-2803D01*
G01X165048D01*
G02Y55480I0J2803D01*
G37*
G36*
G01X176859Y61386D02*
X184733D01*
G02Y55780I0J-2803D01*
G01X176859D01*
G02Y61386I0J2803D01*
G37*
G36*
G01X244450Y233454D02*
X247599D01*
G02Y230848I0J-1303D01*
G01X244450D01*
G02Y233454I0J1303D01*
G37*
G36*
G01X250749Y230304D02*
X253898D01*
G02Y227700I0J-1302D01*
G01X250749D01*
G02Y230304I0J1302D01*
G37*
G36*
G01X162550Y385832D02*
X159050D01*
G02Y388836I0J1502D01*
G01X162550D01*
G02Y385832I0J-1502D01*
G37*
G36*
G01X72150Y425702D02*
X75650D01*
G02Y422696I0J-1503D01*
G01X72150D01*
G02Y425702I0J1503D01*
G37*
G36*
G01X92801Y454296D02*
X96301D01*
G02Y451290I0J-1503D01*
G01X92801D01*
G02Y454296I0J1503D01*
G37*
G36*
G01X60622Y432776D02*
X64122D01*
G02Y429770I0J-1503D01*
G01X60622D01*
G02Y432776I0J1503D01*
G37*
G36*
G01X182350Y384132D02*
X178850D01*
G02Y387136I0J1502D01*
G01X182350D01*
G02Y384132I0J-1502D01*
G37*
G36*
G01X216725Y440718D02*
X213225D01*
G02Y443722I0J1502D01*
G01X216725D01*
G02Y440718I0J-1502D01*
G37*
G36*
G01X159923Y97784D02*
X163423D01*
G02Y94778I0J-1503D01*
G01X159923D01*
G02Y97784I0J1503D01*
G37*
G36*
G01X169347D02*
X172847D01*
G02Y94778I0J-1503D01*
G01X169347D01*
G02Y97784I0J1503D01*
G37*
G36*
G01X221225Y408648D02*
X217725D01*
G02Y411652I0J1502D01*
G01X221225D01*
G02Y408648I0J-1502D01*
G37*
G36*
G01X267722Y175288D02*
X264222D01*
G02Y178294I0J1503D01*
G01X267722D01*
G02Y175288I0J-1503D01*
G37*
G36*
G01X81990Y449588D02*
X85490D01*
G02Y446582I0J-1503D01*
G01X81990D01*
G02Y449588I0J1503D01*
G37*
G36*
G01X52750Y425702D02*
X56250D01*
G02Y422698I0J-1502D01*
G01X52750D01*
G02Y425702I0J1502D01*
G37*
G36*
G01X255213Y107602D02*
X258713D01*
G02Y104596I0J-1503D01*
G01X255213D01*
G02Y107602I0J1503D01*
G37*
G36*
G01X246488Y107294D02*
X249988D01*
G02Y104290I0J-1502D01*
G01X246488D01*
G02Y107294I0J1502D01*
G37*
G36*
G01X266080Y205760D02*
X262580D01*
G02Y208764I0J1502D01*
G01X266080D01*
G02Y205760I0J-1502D01*
G37*
G36*
G01X267080Y213090D02*
X263580D01*
G02Y216096I0J1503D01*
G01X267080D01*
G02Y213090I0J-1503D01*
G37*
G36*
G01X95870Y446986D02*
X99370D01*
G02Y443980I0J-1503D01*
G01X95870D01*
G02Y446986I0J1503D01*
G37*
G36*
G01X375904Y-439648D02*
G02Y-436642I0J1503D01*
G01X379304D01*
G02Y-439648I0J-1503D01*
G01X375904D01*
G37*
G36*
G01X375964Y-217462D02*
G02Y-214456I0J1503D01*
G01X379364D01*
G02Y-217462I0J-1503D01*
G01X375964D01*
G37*
G36*
G01X375876Y-161376D02*
G02Y-158370I0J1503D01*
G01X379276D01*
G02Y-161376I0J-1503D01*
G01X375876D01*
G37*
G36*
G01X397080Y-122524D02*
G02Y-119518I0J1503D01*
G01X400480D01*
G02Y-122524I0J-1503D01*
G01X397080D01*
G37*
G36*
G01X375964Y10810D02*
G02Y13816I0J1503D01*
G01X379364D01*
G02Y10810I0J-1503D01*
G01X375964D01*
G37*
G36*
G01X375904Y66896D02*
G02Y69902I0J1503D01*
G01X379304D01*
G02Y66896I0J-1503D01*
G01X375904D01*
G37*
G36*
G01X375964Y380082D02*
G02Y383088I0J1503D01*
G01X379364D01*
G02Y380082I0J-1503D01*
G01X375964D01*
G37*
G36*
G01X396992Y-465710D02*
G02Y-462704I0J1503D01*
G01X400392D01*
G02Y-465710I0J-1503D01*
G01X396992D01*
G37*
G54D54*
X403692Y-481375D03*
X393692D03*
Y-456375D03*
X403692D03*
X382604Y-455313D03*
X372604D03*
Y-430313D03*
X382604D03*
X382664Y373753D03*
X372664D03*
Y398753D03*
X382664D03*
X393750Y272050D03*
X403750D03*
Y247050D03*
X393750D03*
Y200538D03*
X403750D03*
Y225538D03*
X393750D03*
X393780Y-128853D03*
X403780D03*
Y-103853D03*
X393780D03*
X403750Y-57222D03*
X393750D03*
Y-82222D03*
X403750D03*
X372604Y76231D03*
X382604D03*
Y51231D03*
X372604D03*
X413750Y-57222D03*
Y-82222D03*
X382664Y4481D03*
X372664D03*
Y29481D03*
X382664D03*
X403750Y398810D03*
X413750D03*
Y423810D03*
X403750D03*
X413750Y200538D03*
Y225538D03*
Y272050D03*
Y247050D03*
X372664Y-223791D03*
X382664D03*
Y-198791D03*
X372664D03*
X393750Y398810D03*
Y423810D03*
X372576Y-152041D03*
X382576D03*
Y-177041D03*
X372576D03*
G54D51*
X65945Y297776D03*
G54D47*
X45276Y18465D03*
X17716D03*
X264173Y20040D03*
X291733D03*
G54D53*
X309055Y18465D03*
X336615D03*
G54D52*
X144685Y297776D03*
G54D49*
X56482Y455094D03*
X102190Y64975D03*
G54D50*
X63569Y455094D03*
G54D46*
X-58189Y454331D03*
X340639Y432809D03*
X27300Y68200D03*
X464567Y-498031D03*
Y454331D03*
G54D48*
X105315Y186571D03*
G54D19*
X19200Y102700D03*
X12500Y102000D03*
X19100Y187420D03*
X15922Y224568D03*
Y227168D03*
X18422Y224568D03*
Y227168D03*
X17065Y255712D03*
X13736Y299891D03*
Y303280D03*
X13869Y352239D03*
X14000Y401700D03*
Y406700D03*
Y404200D03*
X17700Y427600D03*
X14600Y422500D03*
X14700Y425000D03*
X25200Y116300D03*
X31890Y110400D03*
X23736Y127758D03*
Y130758D03*
X32236Y127758D03*
Y130758D03*
X21000Y227000D03*
Y224500D03*
X24705Y258767D03*
X22237Y304626D03*
X30638Y304602D03*
X22237Y301237D03*
X30638Y301213D03*
X30700Y315500D03*
X33000Y318700D03*
X23810Y322534D03*
X31300Y329900D03*
X31000Y342500D03*
X26300Y374400D03*
X36200Y368400D03*
X31600Y379600D03*
X32700Y395381D03*
X20600Y428900D03*
X25202Y425329D03*
X29400Y430900D03*
X23677Y422419D03*
X31500Y428500D03*
X32100Y432800D03*
X45500Y41500D03*
X35304Y58317D03*
X45500Y92500D03*
X40340Y100710D03*
X45001Y95144D03*
X48500Y112559D03*
X40940D03*
X40736Y127758D03*
Y130758D03*
X49236Y127758D03*
Y130758D03*
X39408Y195990D03*
X47948Y201000D03*
X39900Y211000D03*
X39493Y222932D03*
X41993D03*
X44149Y227332D03*
X39493Y220332D03*
X41993D03*
X44149Y224732D03*
X48059Y214825D03*
X48023Y217860D03*
X39800Y213800D03*
X35700Y218000D03*
X35600Y241200D03*
Y238200D03*
X51500Y258200D03*
X37485Y258807D03*
X41100Y248900D03*
X46220Y277170D03*
X47440Y304225D03*
X39039Y301299D03*
X47440Y301336D03*
X39039Y304278D03*
X50950Y318050D03*
X43500Y317100D03*
X48420Y321616D03*
X44200Y332000D03*
X44525Y324000D03*
X39100Y321600D03*
X44481Y328760D03*
X38560Y329739D03*
X35500Y340500D03*
Y335000D03*
X44220Y341008D03*
X44500Y344000D03*
X37400Y359900D03*
X44500Y348000D03*
X44525Y360000D03*
X35100Y352400D03*
X44500Y351600D03*
X35900Y363025D03*
X37800Y371225D03*
X44525Y364000D03*
Y368000D03*
X37300Y375000D03*
X44525Y376000D03*
X37875Y377925D03*
X44525Y387800D03*
X37735Y391200D03*
X44525Y391650D03*
X35101Y381610D03*
X44525Y384000D03*
X37020Y385600D03*
X47075Y391730D03*
X44500Y380000D03*
X44490Y397850D03*
X44525Y394150D03*
X36911Y394915D03*
X37067Y398337D03*
X44341Y406480D03*
X44330Y401450D03*
X39530Y409100D03*
X42900Y412900D03*
X46100Y412700D03*
X41200Y429100D03*
X43600Y422800D03*
X42200Y435900D03*
X38000Y428800D03*
X48050Y436350D03*
X45100Y435800D03*
X46100Y422800D03*
X54200Y25400D03*
X58976Y36402D03*
X53600Y44100D03*
X56348Y36210D03*
X50710Y54724D03*
X55000Y76000D03*
X63086Y65762D03*
X52120Y78373D03*
X59240Y67242D03*
X52502Y80978D03*
X53434Y106562D03*
X53400Y102788D03*
X59945Y117795D03*
Y120630D03*
X52237Y129522D03*
X60800Y137000D03*
X61123Y133070D03*
X52876Y195712D03*
X52410Y186900D03*
X59700Y196200D03*
X52410Y190190D03*
X52050Y208760D03*
X64050Y201010D03*
X52948Y200700D03*
X58000Y217700D03*
X58823Y213531D03*
X51600Y241200D03*
X59850Y235830D03*
X51010Y233570D03*
X49700Y242900D03*
X50567Y238630D03*
X50700Y250400D03*
X61200Y282600D03*
X58900Y288075D03*
X54660Y311660D03*
X60613Y312012D03*
X60600Y318000D03*
X64230Y303210D03*
X56600Y320500D03*
Y324300D03*
X52800Y322400D03*
X63000Y324100D03*
X56600Y318000D03*
X52820Y325200D03*
X60225Y336099D03*
X57400Y345400D03*
X52900Y360000D03*
X52600Y376600D03*
X58035Y370100D03*
X54400Y374700D03*
X55294Y369729D03*
X52475Y364000D03*
X52765Y390200D03*
X59500Y394000D03*
X58620Y408779D03*
X63200Y408600D03*
X52330Y413350D03*
X59511Y424477D03*
X60622Y431273D03*
X64122D03*
X56250Y424200D03*
X52750D03*
X54100Y448600D03*
X56500Y447600D03*
X56482Y456844D03*
Y453344D03*
X63569Y456844D03*
Y453344D03*
X68500Y66500D03*
X75280Y75704D03*
X72500Y66500D03*
X74757Y89745D03*
Y92745D03*
Y86745D03*
Y83745D03*
X66830Y122329D03*
X66900Y125300D03*
X66874Y130590D03*
X72300Y159400D03*
X68600Y159160D03*
X76442Y166907D03*
X73550Y166680D03*
X67330Y169267D03*
X68960Y173300D03*
X75284Y180800D03*
X71124Y178565D03*
X75300Y183875D03*
X71146Y186489D03*
X71370Y188993D03*
X67386Y191935D03*
X67486Y188977D03*
X74046Y186490D03*
X71600Y200900D03*
X72150Y204810D03*
X76670Y208772D03*
X75000Y214000D03*
X72500D03*
X70453Y222900D03*
X74583Y217314D03*
X70900Y241500D03*
X71100Y233575D03*
X67700Y229725D03*
X68990Y257000D03*
X77010Y256645D03*
X65755Y256045D03*
X76200Y247400D03*
X73011Y246365D03*
X77384Y253769D03*
X68800Y253300D03*
X68990Y260465D03*
X77437Y262760D03*
X77900Y274700D03*
X70000Y280000D03*
X78600Y283970D03*
X75960Y284049D03*
X65100Y282475D03*
X72700Y301200D03*
X75870Y290700D03*
X78770Y290708D03*
X73400Y313700D03*
X77500Y316100D03*
X68500Y325100D03*
X81000Y321900D03*
X76900Y323000D03*
X76500Y325500D03*
X78700Y340000D03*
X78900Y336600D03*
X71700Y340600D03*
X71000Y394400D03*
X67900Y400525D03*
X79000Y395500D03*
X73976Y408665D03*
X77860Y408678D03*
X77592Y413437D03*
X69139Y413452D03*
X66319Y413492D03*
X74782Y413800D03*
X67000Y408800D03*
X69700D03*
X69030Y422653D03*
X68100Y425400D03*
X71200Y431700D03*
X72150Y424199D03*
X75650D03*
X77600Y431400D03*
X79010Y445750D03*
X72800Y437900D03*
X88000Y66500D03*
X84500D03*
X90151Y68985D03*
X91358Y89745D03*
Y92745D03*
Y86745D03*
Y83745D03*
X86700Y119100D03*
X92500Y116200D03*
X89256Y135056D03*
X86100Y153340D03*
X89170Y141540D03*
X89200Y138800D03*
X86100Y155840D03*
X83410Y161020D03*
X86100Y158390D03*
X83520Y158520D03*
X81500Y176515D03*
X80788Y190812D03*
X82370Y197010D03*
X91300Y252900D03*
X80300Y243700D03*
X80270Y247830D03*
X90800Y258225D03*
X83500Y266900D03*
X84016Y258230D03*
X91500Y267000D03*
X92300Y282100D03*
X90923Y293520D03*
X85500Y326700D03*
X92698Y323224D03*
X93288Y330289D03*
X81900Y337100D03*
X81700Y342600D03*
X90500Y397600D03*
X82500D03*
X89487Y408435D03*
X87600Y414500D03*
X87800Y410300D03*
X84801Y409760D03*
X92500Y408630D03*
X86481Y407871D03*
X96030Y409400D03*
X81552Y409660D03*
X84320Y430510D03*
X93259Y424200D03*
X88565Y426535D03*
X79600Y426400D03*
X81990Y448085D03*
X85490D03*
X92870Y437831D03*
X89700Y437900D03*
X92801Y452793D03*
X107000Y44500D03*
X102190Y63225D03*
X104600Y50501D03*
X98500Y66500D03*
X102190Y66725D03*
X111000Y77000D03*
X104500Y73500D03*
X107124Y71004D03*
X108800Y91900D03*
X104425Y82500D03*
X110950Y82050D03*
X106000Y91900D03*
X111075Y104600D03*
X100360Y116500D03*
X102999Y131799D03*
X108270Y138630D03*
X95950Y152900D03*
X95944Y149687D03*
X98720Y236980D03*
X103580Y237400D03*
X106600Y253689D03*
X95300Y247100D03*
X97177Y263320D03*
X102600Y267000D03*
X107200Y265000D03*
X106800Y262076D03*
X106574Y280028D03*
X106100Y282900D03*
X100700Y293600D03*
X108551Y294241D03*
X99990Y311200D03*
Y307900D03*
X105100Y309300D03*
X94400Y311100D03*
Y307200D03*
X100500Y328547D03*
X105755Y327719D03*
X103000Y323800D03*
X95060Y327625D03*
X106852Y323292D03*
X97800Y325700D03*
X99026Y338368D03*
X103180Y336286D03*
X108108Y395100D03*
X98100Y412400D03*
X105500Y418200D03*
X100457Y409100D03*
X108701Y418300D03*
X98300Y407600D03*
X108336Y411547D03*
X108500Y408680D03*
X109048Y425853D03*
X104112Y422946D03*
X103461Y425875D03*
X95845Y424755D03*
X106700Y447730D03*
X95770Y437920D03*
X95870Y445483D03*
X99370D03*
X103900Y447640D03*
X96301Y452793D03*
X119000Y44600D03*
X115000Y44500D03*
X125800Y47330D03*
X112800Y60400D03*
X112600Y52800D03*
X118500Y75500D03*
X116500Y74000D03*
X109121Y69500D03*
X119700Y89200D03*
X123710Y82300D03*
X123740Y79791D03*
X115025Y104800D03*
X123325Y111000D03*
X120724Y108937D03*
X109350Y115501D03*
X109200Y118500D03*
X120500Y115525D03*
X109200Y128500D03*
X118990Y131580D03*
X109670Y136060D03*
X118692Y137304D03*
X120800Y147200D03*
X117800D03*
X113000Y160700D03*
X115400Y159500D03*
X113000Y158000D03*
X122156Y157844D03*
X122900Y170100D03*
X123120Y213088D03*
X123790Y227656D03*
X123690Y230156D03*
X122876Y242800D03*
X117840Y242200D03*
X121200Y234890D03*
X112200Y234520D03*
X116143Y230790D03*
X112900Y239200D03*
X111400Y254680D03*
X122876Y245300D03*
X120020Y254430D03*
X119105Y251511D03*
X117400Y266500D03*
X109800Y264928D03*
X111600Y262730D03*
X111100Y273700D03*
X111600Y284000D03*
X120070Y273700D03*
X115000D03*
X122957Y300991D03*
X123100Y295974D03*
X120600Y293471D03*
X110565Y296331D03*
X124935Y324900D03*
X115535Y335235D03*
X124300Y348800D03*
X115600Y337900D03*
X114700Y351200D03*
X121200Y359200D03*
X111330Y357800D03*
X120200Y361600D03*
X114700Y348500D03*
X111460Y361770D03*
X111950Y371200D03*
X122047Y372260D03*
X125650Y368650D03*
X122330Y364670D03*
X111869Y365454D03*
X121175Y385125D03*
X119200Y389700D03*
X117410Y381350D03*
X110900Y378500D03*
X123100Y390600D03*
X119200Y406175D03*
X122600Y394600D03*
X119026Y393332D03*
X119791Y412301D03*
X112800Y421600D03*
X113000Y416200D03*
X116632Y411500D03*
X122498Y419675D03*
X112796Y412490D03*
X119500Y433600D03*
X111510Y434710D03*
X121700Y424005D03*
X123170Y433200D03*
X126425Y57000D03*
X133000Y59900D03*
X140730Y72600D03*
X130500Y74700D03*
X129300Y82650D03*
X131470Y81260D03*
X129500Y91475D03*
X131528Y114271D03*
X135500Y138000D03*
Y135000D03*
X134400Y127652D03*
X132828Y138400D03*
X133500Y146800D03*
X138458Y146458D03*
X132500Y167300D03*
X126500Y158000D03*
X133690Y158100D03*
X136190D03*
X126500Y174000D03*
X137900Y179160D03*
X135300Y175100D03*
X125700Y183700D03*
X129810Y191310D03*
X124338Y204742D03*
X124779Y201633D03*
X126153Y199079D03*
X135000Y221200D03*
X132500Y221900D03*
X138100Y213600D03*
X134891Y225171D03*
X124226Y225194D03*
X134358Y230069D03*
X130167Y234733D03*
X138000Y244600D03*
X133000Y256100D03*
X128760Y265726D03*
X127600Y259700D03*
X135315Y279813D03*
X125100Y273720D03*
X128760Y273701D03*
X137083Y278045D03*
X137196Y274491D03*
X132420Y273811D03*
X138600Y295900D03*
X124100Y311100D03*
X136100Y334000D03*
X129800Y325800D03*
X138590Y345710D03*
X124400Y345300D03*
X125910Y335006D03*
X125900Y337600D03*
X133300Y334100D03*
X136000Y341000D03*
X133000Y361500D03*
X132600Y350090D03*
X124350Y352450D03*
X129776Y374500D03*
X138700Y376600D03*
X126340Y382700D03*
X125174Y393916D03*
X135300Y399900D03*
X137900Y399500D03*
X131540Y394690D03*
X132700Y402700D03*
X133500Y409110D03*
X129135Y410250D03*
X133070Y420874D03*
X134300Y416414D03*
X136230Y423935D03*
X128866Y433066D03*
X135350Y433016D03*
X124500Y424005D03*
X132070Y433110D03*
X133572Y423935D03*
X125930Y433110D03*
X138750Y451500D03*
Y454500D03*
X152800Y75600D03*
X145000Y90700D03*
X145100Y87400D03*
X142400Y91300D03*
X141100Y86500D03*
X148819Y123197D03*
X143400Y121700D03*
X141220Y123070D03*
X147600Y117000D03*
X151800Y116500D03*
X152800Y111600D03*
X148819Y125697D03*
X149800Y138100D03*
Y135100D03*
X145185Y134214D03*
X142892Y136645D03*
X143269Y150456D03*
X150155Y145086D03*
X152556Y147683D03*
X148429Y147682D03*
X144500Y169570D03*
X146300Y161010D03*
X140554Y168887D03*
X153200Y170990D03*
X140554Y171688D03*
X146882Y177501D03*
X150619Y178646D03*
X145296Y188835D03*
X140830Y192530D03*
X153051Y187354D03*
X150005Y184973D03*
X149100Y189963D03*
X144280Y195130D03*
X151940Y203710D03*
X151900Y213200D03*
X143980Y199674D03*
X147800Y200789D03*
X140903Y199421D03*
X143742Y203395D03*
X152500Y199500D03*
X145500Y227700D03*
X142702Y227817D03*
X153100Y234800D03*
X149862Y243788D03*
X142085Y230549D03*
X151040Y237870D03*
X145250Y256890D03*
X145580Y248082D03*
X141280Y256310D03*
X149215Y267745D03*
X152400Y284400D03*
X150240Y277940D03*
X152500Y289425D03*
X150293Y302117D03*
X147500Y289405D03*
X141890Y310570D03*
X151320Y322700D03*
X148600Y336300D03*
X142202Y334000D03*
X142300Y336700D03*
X144800D03*
X144700Y334100D03*
X153419Y341978D03*
X143945Y354146D03*
X148316Y359086D03*
X141045Y355309D03*
X150900Y360325D03*
X151695Y357900D03*
X149500Y356700D03*
X141000Y358500D03*
X145703Y370700D03*
X139200Y372510D03*
X149000Y383070D03*
X152100Y378400D03*
X152500Y382600D03*
X150820Y387325D03*
X141520Y399700D03*
X139400Y392460D03*
X151265Y399500D03*
X142511Y393690D03*
X153079Y412000D03*
X149600Y410500D03*
X139700Y415100D03*
X150000Y414750D03*
X143000Y414600D03*
X140600Y412300D03*
X148060Y423500D03*
X148100Y433400D03*
X152200Y423100D03*
X148041Y426700D03*
X138987Y423935D03*
X151398Y449930D03*
X158246Y78872D03*
X156710Y73420D03*
X163423Y96281D03*
X159923D03*
X166200Y105500D03*
X155530Y116640D03*
X156286Y124903D03*
X156200Y111600D03*
X162657Y117297D03*
X154050Y137100D03*
X159000Y135000D03*
X166700Y132360D03*
X156406Y129203D03*
X162419Y131032D03*
X166733Y128700D03*
X155325Y139440D03*
X153954Y145086D03*
X161900Y150500D03*
X165690Y149622D03*
X159328Y160847D03*
X156481Y155933D03*
X162200Y158200D03*
X159900Y155600D03*
X161240Y177820D03*
X161237Y181735D03*
X156467Y203500D03*
X162594Y212585D03*
Y210085D03*
X166140Y205955D03*
X165381Y201274D03*
X153744Y217435D03*
X153800Y214900D03*
X162653Y218843D03*
X159643Y226484D03*
X162200Y221376D03*
X163500Y229184D03*
X167200Y222600D03*
X161200Y233600D03*
X165500Y236100D03*
X157200Y240000D03*
X156970Y255000D03*
X165013Y254986D03*
X160973D03*
X164500Y266000D03*
X160590Y263300D03*
X156970Y263250D03*
X164800Y263300D03*
X158750Y284949D03*
X168392Y298493D03*
X160850Y301344D03*
X168300Y301100D03*
X162100Y291600D03*
X161400Y307600D03*
X162160Y313560D03*
X170800Y317600D03*
X164500Y314800D03*
X155000Y321100D03*
X168557Y341221D03*
X158459Y340898D03*
X158467Y344067D03*
X161300Y354600D03*
X161154Y376704D03*
X156300Y376300D03*
X154500Y387350D03*
X159050Y387334D03*
X162550D03*
X165500Y386000D03*
X165501Y382800D03*
X158200Y381400D03*
X155452Y401000D03*
X160540Y416912D03*
X162100Y414000D03*
X157294Y435623D03*
X156101Y425100D03*
X167008Y430718D03*
X165500Y433100D03*
X167865Y427771D03*
X163700Y422119D03*
X159396Y449408D03*
X160700Y445550D03*
X158100Y442700D03*
X168029Y456660D03*
X157500Y453390D03*
X176900Y14625D03*
X178200Y76145D03*
X175700Y76245D03*
X179900Y91300D03*
X181960Y99260D03*
X169700Y102250D03*
X176300Y98700D03*
X172847Y96281D03*
X169347D03*
X179500Y116800D03*
X182000Y117200D03*
X171600Y114000D03*
X182865Y113706D03*
X174600Y114000D03*
X169100Y113900D03*
X182103Y132294D03*
X182108Y129094D03*
X170867Y128211D03*
X178290Y128824D03*
X174553Y128728D03*
X176550Y125210D03*
X178284Y132394D03*
X170610Y131900D03*
X174436Y132394D03*
X168800Y126800D03*
X172100Y146300D03*
X176000Y140500D03*
X172890Y153260D03*
X171700Y156900D03*
X169500Y180200D03*
X170800Y193100D03*
X172621Y208300D03*
X173800Y225400D03*
X170400Y214700D03*
X172400Y220700D03*
X175300Y240000D03*
X174400Y254736D03*
X179846Y255150D03*
X180458Y258825D03*
X174400Y251936D03*
X176900Y270100D03*
X174292Y263300D03*
X171592Y263312D03*
X168710Y272256D03*
X172977Y277000D03*
X182435Y281797D03*
X179217Y278528D03*
X168656Y275156D03*
X182232Y296424D03*
X174232Y304333D03*
X176563Y310917D03*
X176533Y314049D03*
X170550Y304050D03*
X169077Y308677D03*
X170561Y306631D03*
X181050Y332250D03*
X171098Y341224D03*
X182700Y342216D03*
X180600Y360200D03*
X177500Y369100D03*
X178850Y385634D03*
X182350D03*
X172530Y420950D03*
Y429470D03*
X184480Y429370D03*
X171400Y450600D03*
X193100Y69100D03*
X189400Y69600D03*
X184800Y100300D03*
X187700Y99000D03*
X187400Y101500D03*
X190800Y117200D03*
X193096Y115600D03*
X186891Y113991D03*
X190744Y114456D03*
X187069Y116800D03*
X184729Y115820D03*
X187435Y129623D03*
X195983Y132294D03*
X191482Y129294D03*
X195983D03*
X186200Y125600D03*
X184000Y140500D03*
X196577Y141185D03*
X189700Y140400D03*
X191693Y236370D03*
X196240Y253430D03*
X193084Y257400D03*
X194567Y255288D03*
X187400Y255700D03*
X190900Y271700D03*
X193386Y269142D03*
X184200Y264900D03*
X185000Y270700D03*
X195370Y273297D03*
X183625Y273500D03*
X196200Y278200D03*
X196100Y281820D03*
X187623Y297475D03*
X192380Y291900D03*
X196443Y294065D03*
X191199Y300200D03*
X192448Y308314D03*
X195031Y307182D03*
X194600Y313300D03*
X197853Y307200D03*
X197155Y314223D03*
X188546Y326356D03*
X190465Y344426D03*
X190600Y337900D03*
X183800Y345400D03*
X197775Y346617D03*
X194800Y341700D03*
X191408Y357451D03*
X197450Y356560D03*
X196050Y358770D03*
X191420Y354710D03*
X190965Y348090D03*
X197711Y349250D03*
X195000Y373900D03*
X187400Y379400D03*
X197400Y367600D03*
Y370250D03*
X197620Y385425D03*
X187300Y384300D03*
X197660Y390870D03*
X190050Y389140D03*
X190100Y392270D03*
X191843Y403995D03*
X189054Y397500D03*
X194500Y402600D03*
X195800Y396780D03*
X185245Y417500D03*
X190370Y422490D03*
X195000Y422540D03*
X199940Y423700D03*
X197600Y415400D03*
X190270Y409962D03*
X189762Y429177D03*
X195300Y432327D03*
X189766Y432050D03*
X189838Y434910D03*
X186720Y432490D03*
X186300Y448700D03*
X185000Y451500D03*
Y454000D03*
Y456500D03*
X191780Y453300D03*
Y456700D03*
X211400Y59238D03*
X204300Y60600D03*
X201500Y61000D03*
X209142Y53664D03*
X204100Y67400D03*
X201900Y83300D03*
X199940Y117500D03*
X211370Y117000D03*
X208200Y111760D03*
X199985Y132294D03*
X212757Y127064D03*
X212727Y129654D03*
X208627Y132394D03*
X208576Y128957D03*
X204120Y132294D03*
X200000Y128764D03*
X208500Y126057D03*
X212727Y132154D03*
X211490Y143700D03*
X205598Y140480D03*
X203542Y213254D03*
X206200Y255385D03*
X200680Y257540D03*
X206051Y247911D03*
X205500Y258300D03*
X201100Y265120D03*
X214034Y261482D03*
X201000Y262500D03*
X203090Y269229D03*
X205590Y269129D03*
X205900Y266130D03*
X204258Y286691D03*
X213258Y273265D03*
X204560Y301130D03*
X212911Y293869D03*
X206430Y298780D03*
X199729Y314565D03*
X198672Y318175D03*
X208628Y324665D03*
X200300Y328800D03*
X208000Y373240D03*
X208565Y404501D03*
X200222Y398150D03*
X213200Y399166D03*
X199880Y402846D03*
X207539Y408686D03*
X200000Y407040D03*
X205223Y422665D03*
X207278Y416022D03*
X206150Y412821D03*
X198600Y426600D03*
X202513Y434800D03*
X198405D03*
X199000Y444500D03*
X205200Y445400D03*
X213225Y442220D03*
X214306Y62233D03*
X229900Y61000D03*
X224000Y74275D03*
X218600Y92100D03*
X221300D03*
X224330Y83210D03*
X227760Y82524D03*
X219900Y101300D03*
X216400Y106400D03*
X226040Y101220D03*
X222890Y101240D03*
X215294Y117094D03*
X226887Y117297D03*
X223300Y117400D03*
X217262Y129294D03*
X225284Y132294D03*
X229342Y129240D03*
X221278Y129294D03*
X225284D03*
X217262Y132294D03*
X221278D03*
X225300Y125200D03*
X227700Y151900D03*
X221000Y243000D03*
X220100Y237200D03*
X223800Y254800D03*
X227316Y256700D03*
X215100Y244100D03*
X215500Y247111D03*
X216800Y255550D03*
X215510Y253310D03*
X225275Y246000D03*
X217500Y264000D03*
X230196Y267477D03*
X219900Y267100D03*
X220866Y272160D03*
X227232Y270539D03*
X226405Y266335D03*
X222833Y261668D03*
X219722Y286728D03*
X227841Y275773D03*
X219339Y284138D03*
X219359Y281580D03*
X226500Y273000D03*
X229220Y283250D03*
X223646Y293960D03*
X214400Y303997D03*
X216384Y312216D03*
X228800Y312100D03*
X226100Y325065D03*
X217300Y322800D03*
X225867Y345033D03*
X225650Y337520D03*
X221000Y343800D03*
X216405Y335970D03*
X214175Y333740D03*
X228230Y340040D03*
X221000Y352000D03*
X224632Y369825D03*
X225700Y362500D03*
X213490Y373690D03*
X226710Y364815D03*
X223420Y367080D03*
X220515Y384900D03*
X222575Y387625D03*
X227206Y400100D03*
X217390Y401340D03*
X222986Y400323D03*
X220134Y400780D03*
X219050Y418850D03*
X217725Y410150D03*
X221225D03*
X226830Y435170D03*
X225000Y433100D03*
X219250Y422150D03*
X213900Y436000D03*
X217100Y436100D03*
X224000Y449100D03*
X216725Y442220D03*
X237000Y47200D03*
X234537Y74638D03*
X240000Y67400D03*
X230600Y91700D03*
X239660Y91920D03*
X232150Y82480D03*
X235630Y104990D03*
X231592Y110500D03*
X240160Y107000D03*
X240710Y99570D03*
X232325Y101230D03*
X236648Y100739D03*
X238900Y114800D03*
X234500Y117500D03*
X230293Y117417D03*
X239900Y117550D03*
X239206Y112300D03*
X233511Y132594D03*
X234900Y126100D03*
X229396Y132294D03*
X233511Y129594D03*
X242500Y129000D03*
X242195Y141003D03*
X232384Y148884D03*
X230535Y244564D03*
X237700Y257387D03*
X237730Y248085D03*
X242690Y255300D03*
X230000Y255700D03*
X232300Y261200D03*
X239298Y268800D03*
X242940Y268500D03*
X233033Y266483D03*
X229630Y264404D03*
X242087Y271427D03*
X238531Y263081D03*
X231900Y272700D03*
X241188Y279347D03*
X241263Y282654D03*
X234500Y293500D03*
X242700Y306800D03*
X240500Y316575D03*
X236688Y311217D03*
X238400Y304200D03*
X228800Y305500D03*
X235400Y303800D03*
X242592Y330683D03*
X243010Y323400D03*
X230445Y325945D03*
X235000Y335300D03*
X231689Y334896D03*
X233500Y346911D03*
Y343911D03*
X231500Y352500D03*
X233650Y359628D03*
X233800Y354300D03*
X230287Y373100D03*
X232470Y382280D03*
X233600Y377300D03*
X233790Y384490D03*
X239750Y394970D03*
X236670Y394550D03*
X241231Y407285D03*
X236860Y407300D03*
X229900Y436600D03*
X236900Y440565D03*
X239500Y447750D03*
X235400Y451600D03*
X231250Y447000D03*
X235200Y449100D03*
X231400Y449500D03*
X241436Y445784D03*
X240200Y450650D03*
X236221Y454400D03*
X240010Y456000D03*
X240210Y453400D03*
X231400Y452000D03*
X252925Y54000D03*
X249475Y55812D03*
X256000Y56000D03*
X246200Y74600D03*
X253000Y77500D03*
X250000Y73000D03*
X255000Y82700D03*
X257800Y82800D03*
X256900Y87300D03*
X251200Y93800D03*
X251900Y100100D03*
X255213Y106099D03*
X249988Y105792D03*
X246488D03*
X244208Y97302D03*
X247200Y117400D03*
X253100Y119900D03*
X245310Y113910D03*
X245500Y127800D03*
X245520Y130600D03*
X258500Y146400D03*
X251354Y152877D03*
X249300Y237600D03*
X247689Y247929D03*
X253110Y254909D03*
X253100Y257800D03*
X252639Y247885D03*
X256700Y263800D03*
X255700Y260000D03*
X247470Y269990D03*
X250288Y273581D03*
X251459Y286542D03*
Y283542D03*
X257145Y279700D03*
X246514Y294325D03*
Y296825D03*
X258100Y295080D03*
X254355Y300577D03*
X247923Y316400D03*
X245900Y305000D03*
X257900Y312100D03*
X248900Y304900D03*
X247923Y319000D03*
X253320Y323327D03*
X256124Y336355D03*
X243750Y369730D03*
X243700Y372730D03*
X244790Y375910D03*
X248800Y385700D03*
X249400Y410300D03*
X252350Y412850D03*
X257810Y435100D03*
X246700Y451500D03*
X246500Y448500D03*
X243375Y448375D03*
X246700Y454100D03*
X259000Y47500D03*
X267939Y41122D03*
X268500Y45500D03*
X259894Y90072D03*
X263102Y91725D03*
X272505Y83545D03*
X260050Y87026D03*
X265801Y106040D03*
X260970Y98600D03*
X258713Y106099D03*
X264989Y101732D03*
X271602Y121400D03*
X269561Y130987D03*
X271300Y132900D03*
X269493Y138604D03*
X260200Y132395D03*
X260388Y125001D03*
X268442Y153299D03*
X265942D03*
Y150799D03*
X268442D03*
X269004Y144450D03*
Y141950D03*
X269133Y164982D03*
X265226D03*
X268339Y222126D03*
X272300Y251000D03*
X258628Y247600D03*
X258475Y254872D03*
X267100Y265000D03*
X269016Y266991D03*
X259500Y263700D03*
X262730Y267600D03*
X258000Y266300D03*
X266600Y268700D03*
X262700Y265100D03*
X258000Y284900D03*
X262100Y280700D03*
X266250Y297900D03*
X266200Y294800D03*
X261500Y290440D03*
X266300Y307500D03*
X262310Y311225D03*
X264265Y315817D03*
X261300Y334100D03*
X271100Y346575D03*
X259420Y343230D03*
Y340630D03*
X273580Y354250D03*
X271990Y362360D03*
X265320Y392290D03*
X274190Y408900D03*
X265100Y395100D03*
X272400Y392400D03*
X269700Y411379D03*
X271500Y418300D03*
X267100Y432900D03*
X263800Y430300D03*
X272999Y430500D03*
X271710Y449840D03*
X266727Y443185D03*
X261700Y439700D03*
X265130Y440070D03*
X261100Y443500D03*
X269561Y456044D03*
X286000Y47000D03*
X277000Y51665D03*
X274500Y58000D03*
X279934Y51688D03*
X279800Y72700D03*
X290000Y82000D03*
X273400Y92800D03*
X276400Y92300D03*
X287578Y84092D03*
X283500Y89500D03*
X277505Y83545D03*
X282505D03*
X278300Y95019D03*
X274760Y105140D03*
X275386Y102710D03*
X280910Y102880D03*
X288116Y120306D03*
X285250Y117250D03*
X274200Y109500D03*
X280400Y126000D03*
X283500D03*
X275960Y126010D03*
X273450Y125050D03*
X287796Y131542D03*
X288280Y126212D03*
X280616Y150971D03*
X283616D03*
X287555Y142419D03*
X285899Y153542D03*
X283399D03*
X279457Y171318D03*
X279983Y235254D03*
X282483D03*
X283974Y251372D03*
X286800Y251400D03*
X276200Y251500D03*
X280082Y251328D03*
X280030Y267098D03*
Y264098D03*
X284357Y267027D03*
Y264027D03*
X285911Y269899D03*
X281889D03*
X287755Y287538D03*
X282911Y279569D03*
X285911D03*
X287507Y301596D03*
X281300Y308800D03*
X287050Y305850D03*
X289939Y309060D03*
X276660Y316900D03*
X273355Y330001D03*
X286372Y320700D03*
X289600Y322253D03*
X286372Y326768D03*
X285860Y336131D03*
X277500Y348469D03*
X275520Y357910D03*
X277290Y355820D03*
X277572Y351198D03*
X287761Y366200D03*
X287500Y376900D03*
X276145Y366455D03*
X276400Y370400D03*
X283664Y379236D03*
X273100Y381500D03*
X283973Y382553D03*
X285191Y390840D03*
X287630Y389378D03*
X275700Y403500D03*
X277700Y406100D03*
X287476Y396680D03*
X278900Y421400D03*
X281300Y416200D03*
X277700Y412580D03*
X287500Y416100D03*
X278409Y433722D03*
X276400Y431810D03*
X275100Y427682D03*
X274619Y424725D03*
X283622Y447155D03*
X275138Y451215D03*
X276632Y439502D03*
X283674Y449975D03*
X283715Y452769D03*
X297466Y51521D03*
X300425Y54516D03*
X290000Y67975D03*
X297575Y73738D03*
X293773Y73530D03*
X300070Y84000D03*
X294600Y106900D03*
X298575Y101900D03*
X304000Y116500D03*
X294800Y111800D03*
X298975Y118900D03*
X301000Y121016D03*
X300500Y125000D03*
X295075Y119100D03*
X301000Y129900D03*
X290200Y129500D03*
X298005Y151118D03*
Y148618D03*
Y146118D03*
X292204Y142610D03*
X301936Y143897D03*
X296734Y216079D03*
X290586Y234844D03*
X288086D03*
X301120Y235626D03*
Y238765D03*
X299138Y244513D03*
X291500Y287670D03*
Y285170D03*
X298840Y279640D03*
X291000Y297700D03*
X291300Y315900D03*
X290120Y339370D03*
X290000Y335600D03*
X300700Y341300D03*
X295500Y354920D03*
X296780Y371500D03*
X298152Y393332D03*
X292700Y403700D03*
X291623Y447747D03*
X291703Y450819D03*
X295729Y453912D03*
Y456912D03*
Y459912D03*
X297738Y452418D03*
Y458418D03*
Y455418D03*
X316025Y60200D03*
X309570Y84000D03*
X316066Y108407D03*
X315100Y116400D03*
X307400Y122300D03*
X315900Y125900D03*
X313800Y124300D03*
X307560Y128500D03*
X305936Y143897D03*
X309936D03*
X313936D03*
X307487Y219503D03*
X304987D03*
X310449Y218617D03*
X317110Y219140D03*
X309521Y235352D03*
Y238741D03*
X305000Y252400D03*
X307600Y252300D03*
X307800Y259200D03*
X312272Y282107D03*
X302800Y286200D03*
X311670Y285160D03*
X302879Y282487D03*
Y279686D03*
X309700Y294789D03*
X306500Y301500D03*
X303000Y309200D03*
X306200Y308800D03*
X312300Y340700D03*
X308906Y362637D03*
X314340Y373296D03*
X311925Y366475D03*
X308926Y401900D03*
X321800Y60055D03*
X322500Y102900D03*
X320500Y100400D03*
X324011Y118843D03*
X324023Y121943D03*
Y115643D03*
X320765Y114582D03*
X320938Y122677D03*
X318000Y117200D03*
X331741Y138243D03*
Y125796D03*
X317936Y143897D03*
X323509Y153377D03*
X329005Y152657D03*
X328087Y141608D03*
X331641Y141743D03*
X321600Y142100D03*
X331405Y164911D03*
Y159911D03*
Y154911D03*
Y167411D03*
Y179911D03*
Y174911D03*
Y169911D03*
Y182926D03*
Y172411D03*
Y189911D03*
X320054Y195163D03*
X326932Y205685D03*
X326733Y209885D03*
X321045Y210257D03*
X320937Y212839D03*
X326733Y201485D03*
X320054Y198663D03*
X326731Y213648D03*
X320931Y215387D03*
X317922Y238717D03*
Y235328D03*
X326323Y235304D03*
Y238693D03*
X327162Y278972D03*
X325007Y328608D03*
Y326008D03*
X327704Y328635D03*
Y326035D03*
X325007Y323508D03*
X327704Y323535D03*
X329925Y356016D03*
X325900Y365643D03*
X326100Y375717D03*
X326200Y370681D03*
X331500Y383300D03*
X326375Y380724D03*
X325593Y406500D03*
X329093D03*
X318593D03*
X322093D03*
X339900Y69100D03*
Y66000D03*
X339908Y104577D03*
Y108593D03*
X342200Y100500D03*
X342180Y106900D03*
X339908Y112609D03*
X339369Y151952D03*
X339939Y162911D03*
X339812Y173380D03*
X339800Y182926D03*
X337400Y193449D03*
X334724Y238669D03*
Y235280D03*
X337467Y236984D03*
X336461Y283202D03*
X340612Y278972D03*
X339700Y293000D03*
X347100Y313700D03*
X345500Y342690D03*
X335475Y358500D03*
Y367500D03*
X335708Y372008D03*
X335500Y380000D03*
X375904Y-438145D03*
X375964Y-215959D03*
X375876Y-159873D03*
X375964Y12313D03*
X375904Y68399D03*
X375964Y381585D03*
X379304Y-438145D03*
X379364Y-215959D03*
X379276Y-159873D03*
X379364Y12313D03*
X379304Y68399D03*
X379364Y381585D03*
X396992Y-464207D03*
X400392D03*
X397080Y-121021D03*
X400480D03*
G54D23*
X23819Y339154D03*
Y359154D03*
Y369154D03*
Y379154D03*
Y389154D03*
Y399154D03*
Y409154D03*
X65709Y42244D03*
Y52244D03*
X75709Y42244D03*
Y52244D03*
X95709Y42244D03*
X85709D03*
Y52244D03*
G54D25*
X63898Y24764D03*
X73898D03*
X90472D03*
X100472D03*
X117047D03*
X127047D03*
X211142D03*
X237717D03*
X247717D03*
G54D28*
X62458Y346425D03*
Y343275D03*
Y355873D03*
X58564Y354280D03*
X65607Y352724D03*
Y359023D03*
Y371584D03*
X75056Y346425D03*
X68757D03*
X81355D03*
X78206Y349574D03*
X71906D03*
X68757D03*
X78206Y359023D03*
X75056Y352724D03*
Y349574D03*
X78206Y355873D03*
X65607D03*
X68757Y362173D03*
Y359023D03*
X71906D03*
X75056Y355873D03*
X71906Y352724D03*
X68757Y355873D03*
X78206Y374733D03*
Y362173D03*
X75056D03*
X71906Y371584D03*
X75056Y365322D03*
X71906D03*
X68757D03*
Y371584D03*
X75056Y374733D03*
X71906D03*
X68757D03*
X65607D03*
X71906Y362173D03*
X78206Y365322D03*
Y371584D03*
X68757Y377883D03*
X78206Y381033D03*
X65607D03*
X71906Y377883D03*
X65607Y384182D03*
X68719Y381033D03*
X78206Y377883D03*
X71906Y387332D03*
X71869Y381033D03*
X71906Y384182D03*
X87617Y352724D03*
X90766Y349574D03*
X93916Y352724D03*
X81355Y355873D03*
X90766Y352724D03*
X87617Y349574D03*
X90766Y355873D03*
X87617D03*
X90766Y359023D03*
X81355Y349574D03*
X87617Y359023D03*
X90766Y374733D03*
Y362173D03*
X81355D03*
X87617D03*
X81355Y374733D03*
X87617D03*
X90766Y371584D03*
Y365322D03*
X81355Y377883D03*
Y387332D03*
Y384182D03*
X87617D03*
X90766Y377883D03*
X87617Y390481D03*
X81355Y381033D03*
X87617Y387332D03*
X90766Y381033D03*
X87617Y377883D03*
X90766Y390481D03*
Y387332D03*
Y384182D03*
X92360Y394175D03*
X89210D03*
X103365Y346425D03*
X106564Y346400D03*
X100253Y346387D03*
X93916Y349574D03*
X97066D03*
X106515Y352724D03*
X106514Y349574D03*
X97066Y352724D03*
X100215Y355873D03*
X93916D03*
X100215Y349574D03*
Y387332D03*
X97066D03*
X93916Y384182D03*
X97066D03*
X100215Y381033D03*
X93916D03*
Y387332D03*
X166300Y212300D03*
X181495Y153449D03*
X175196Y159748D03*
X178346Y156599D03*
X181495Y159748D03*
X175196Y156599D03*
X181495D03*
Y166047D03*
X184645D03*
X181495Y162898D03*
X178346Y159748D03*
X181495Y178646D03*
Y175496D03*
X184645Y181795D03*
X181495D03*
Y172347D03*
X184645Y175496D03*
X174569Y180202D03*
X178346Y175496D03*
X175196Y172347D03*
X173000Y170200D03*
X181495Y169197D03*
Y184945D03*
Y197506D03*
X178346D03*
Y191244D03*
X181495D03*
X175196Y197506D03*
X174336Y192800D03*
X181495Y188095D03*
X178346D03*
X175196Y200655D03*
X178346Y210104D03*
X181495Y203805D03*
Y206955D03*
X175196Y210104D03*
X178346Y206955D03*
X175196D03*
Y203805D03*
X178346D03*
X171836Y200655D03*
Y198300D03*
X181495Y200655D03*
Y219553D03*
X175196Y213254D03*
X184645Y219553D03*
X178346Y229002D03*
X181495Y225852D03*
Y222703D03*
X184645Y229002D03*
X174600Y217800D03*
X181495Y216403D03*
X175196Y229002D03*
X181495D03*
X187794Y153449D03*
X192400Y152804D03*
X184645Y153449D03*
X197243Y166047D03*
X194094Y162898D03*
X197243Y159748D03*
X194094D03*
X197243Y162898D03*
X184645Y156599D03*
X187794Y162898D03*
Y166047D03*
X184645Y162898D03*
Y159748D03*
X190944Y162898D03*
Y159748D03*
X194094Y166047D03*
X190944D03*
X200393Y162898D03*
X187794Y156599D03*
Y178646D03*
X194094Y169197D03*
X190944Y172347D03*
Y175496D03*
X197243D03*
X190944Y178646D03*
Y181795D03*
X187794Y175496D03*
X184645Y178646D03*
X190944Y169197D03*
X187794Y172347D03*
X184645Y169197D03*
Y172347D03*
X187794Y169197D03*
X197243Y184945D03*
X190944Y197506D03*
Y184945D03*
Y188095D03*
Y191244D03*
X187794Y197506D03*
Y184945D03*
X184645Y197506D03*
Y184945D03*
Y191244D03*
Y188095D03*
X190944Y200655D03*
Y210104D03*
Y203805D03*
X187794Y200655D03*
X184645Y210104D03*
Y200655D03*
Y203805D03*
X187794Y210104D03*
X190944Y219553D03*
X194094Y222703D03*
X200393Y229002D03*
X194094Y225852D03*
X187794D03*
Y219553D03*
X190944Y213254D03*
Y222702D03*
X200393Y222703D03*
X197243Y225852D03*
Y222703D03*
X184645Y225852D03*
X187794Y222703D03*
X184645D03*
Y213254D03*
X194094Y219553D03*
X187794Y229002D03*
X197243Y235301D03*
X194094Y229002D03*
X197243D03*
Y232151D03*
X209842Y153449D03*
Y159748D03*
X206692Y156599D03*
X203542Y166047D03*
X206692Y162898D03*
X203542D03*
X200393Y159748D03*
X209842Y166047D03*
Y162898D03*
X212991D03*
X203542Y159748D03*
X200393Y166047D03*
X206692D03*
X212991D03*
X206692Y159748D03*
X209842Y169197D03*
X206692Y181795D03*
X203542Y175496D03*
X206692D03*
X209842D03*
X200393D03*
X212991Y184945D03*
Y197506D03*
X203542Y206955D03*
X212991Y203805D03*
X206692Y206955D03*
X209842D03*
X200393D03*
X212991Y200655D03*
Y213254D03*
X200393D03*
Y219553D03*
X212991Y222740D03*
X209842Y213254D03*
Y225852D03*
X203542Y222703D03*
X200393Y225852D03*
X206692Y219553D03*
X203542Y225852D03*
X206692Y229002D03*
X212991D03*
X203542Y219553D03*
X206692Y222703D03*
X209842D03*
X212991Y225890D03*
X206692Y225852D03*
X203542Y229002D03*
X209746Y235397D03*
X203542Y235301D03*
X209842Y232151D03*
X200393D03*
X206692D03*
X212991D03*
X209842Y229002D03*
X225658Y153369D03*
X225552Y159748D03*
X222402Y162898D03*
X219253Y166047D03*
X225552Y162898D03*
Y166047D03*
X222402D03*
X219253Y159748D03*
X222402D03*
X219253Y162898D03*
Y156599D03*
X222402D03*
Y178646D03*
X225552Y181795D03*
X214547Y174852D03*
X225552Y169197D03*
X219253D03*
X225552Y191244D03*
Y188095D03*
X222402Y191244D03*
X219253Y197506D03*
X222402D03*
X219253Y188095D03*
Y200655D03*
Y206955D03*
Y210104D03*
Y203805D03*
Y213254D03*
X228739Y222703D03*
X216141D03*
X228702Y229002D03*
X225590Y222720D03*
X216103Y219591D03*
X219253Y219553D03*
X225590Y225852D03*
X222440Y222703D03*
X225552Y219553D03*
X222402D03*
Y229002D03*
X222440Y225852D03*
X219290D03*
Y222703D03*
X225552Y229002D03*
X219253D03*
X235001Y153449D03*
X228702Y162898D03*
X238150D03*
X231851Y166047D03*
X238150D03*
X228702Y159748D03*
Y166047D03*
X238150Y156599D03*
X235001D03*
X231851D03*
Y162898D03*
Y159748D03*
X235001Y162898D03*
Y159748D03*
X238150D03*
X241300D03*
X231851Y169197D03*
Y178646D03*
X235001Y169197D03*
X241300Y175496D03*
Y178646D03*
Y172347D03*
X235001Y178646D03*
Y175496D03*
X228702Y181795D03*
Y178646D03*
X235001Y188095D03*
Y191244D03*
Y197506D03*
X241300Y184945D03*
Y197506D03*
Y188095D03*
X244450Y200655D03*
X228702D03*
X235001Y203805D03*
X231851D03*
X228702D03*
X241300Y200655D03*
Y210104D03*
X235001D03*
X231851D03*
X228702D03*
X235038Y225890D03*
X228739Y225852D03*
X238150Y222703D03*
X231889Y219591D03*
Y222740D03*
X235038D03*
X231889Y225890D03*
X228739Y216441D03*
X241338Y225890D03*
X231851Y229002D03*
X241300D03*
X239870Y237596D03*
X242870D03*
X235038Y229039D03*
X250749Y169197D03*
X247637Y162898D03*
X247599Y166047D03*
X253898Y169197D03*
X257048Y172347D03*
X250749Y181795D03*
X244450D03*
X250749Y175496D03*
Y178646D03*
X247599Y172347D03*
X244450Y175496D03*
X250749Y172347D03*
X247599Y178646D03*
X253898Y175496D03*
X244450Y178646D03*
Y172347D03*
X250749Y184945D03*
X244450Y169197D03*
Y197506D03*
X247599Y191244D03*
X257048Y197506D03*
X253898D03*
X250749D03*
X247599Y184945D03*
X244450Y188095D03*
X257048Y191244D03*
X250749Y188095D03*
X244450Y184945D03*
X250749Y191244D03*
X244450D03*
X250749Y203805D03*
X247599Y206955D03*
Y210104D03*
X250749Y206955D03*
X247599Y200655D03*
X257048Y206955D03*
X250749Y200655D03*
X257048D03*
X250749Y210104D03*
X244450Y203805D03*
X250749Y222703D03*
Y225852D03*
X253898Y219553D03*
Y222703D03*
X257048Y213254D03*
X250749D03*
X247599D03*
X253898D03*
X247637Y225852D03*
X244450Y232151D03*
X247599D03*
X253898D03*
X257048D03*
X250749Y229002D03*
X253898D03*
X250749Y235301D03*
X253898D03*
X267722Y176791D03*
X264222D03*
X271209Y177524D03*
X270472Y188488D03*
X264118Y188095D03*
X266080Y207262D03*
X262580D03*
X263580Y214593D03*
X267080D03*
X285482Y168102D03*
X273644Y174267D03*
X282975Y172975D03*
X286105Y176085D03*
X289254Y194839D03*
X286105Y185534D03*
Y194839D03*
Y204288D03*
X286106Y210587D03*
X286105Y213721D03*
X289110Y163487D03*
X292260D03*
X295410Y169786D03*
X292404Y176085D03*
X295410Y172936D03*
X289254Y172792D03*
X292260Y169643D03*
X295410Y179235D03*
X292384Y172936D03*
X289254Y176085D03*
Y182385D03*
X292260Y179235D03*
X289111D03*
X292404Y191690D03*
X289254D03*
X292404Y185534D03*
Y194983D03*
X295410Y194839D03*
X295411Y185534D03*
X289254D03*
Y197989D03*
X298714Y210477D03*
X292404Y210587D03*
Y201282D03*
X299667Y201334D03*
X292404Y213737D03*
X289254Y201139D03*
X295410Y210587D03*
X311158Y163487D03*
X308008Y166637D03*
X314307Y163487D03*
X314930Y168140D03*
Y171289D03*
Y177588D03*
X305002Y176085D03*
Y169786D03*
Y172936D03*
X308152Y169786D03*
X311158Y169643D03*
X308152Y172936D03*
Y176085D03*
Y182385D03*
X305002Y179235D03*
X308152D03*
X314930Y180738D03*
Y174439D03*
X308008Y191690D03*
X311158D03*
X308008Y188540D03*
Y185391D03*
Y198133D03*
X314307Y185534D03*
X311158Y188540D03*
X308008Y194839D03*
X311158Y197989D03*
X314307Y194839D03*
Y197989D03*
X308008Y207438D03*
X308152Y204432D03*
X305002D03*
X311158Y210587D03*
X308008Y210731D03*
X305002Y210587D03*
X314307Y201139D03*
Y204288D03*
Y210587D03*
Y213737D03*
G54D39*
X372604Y-455313D03*
Y-430313D03*
X372664Y-223791D03*
Y-198791D03*
X372576Y-177041D03*
Y-152041D03*
X372664Y4481D03*
Y29481D03*
X372604Y51231D03*
Y76231D03*
X372664Y373753D03*
Y398753D03*
X393692Y-481375D03*
X382604Y-455313D03*
X393692Y-456375D03*
X382604Y-430313D03*
X382664Y-223791D03*
Y-198791D03*
X382576Y-177041D03*
Y-152041D03*
X393780Y-128853D03*
Y-103853D03*
X393750Y-82222D03*
Y-57222D03*
X382664Y4481D03*
Y29481D03*
X382604Y51231D03*
Y76231D03*
X393750Y200538D03*
Y225538D03*
Y247050D03*
Y272050D03*
X382664Y373753D03*
X393750Y398810D03*
X382664Y398753D03*
X393750Y423810D03*
X403692Y-481375D03*
Y-456375D03*
X403780Y-128853D03*
Y-103853D03*
X403750Y-82222D03*
D03*
Y-57222D03*
D03*
Y200538D03*
D03*
Y225538D03*
D03*
Y247050D03*
D03*
Y272050D03*
D03*
Y398810D03*
D03*
Y423810D03*
D03*
X413750Y-82222D03*
Y-57222D03*
Y200538D03*
Y225538D03*
Y247050D03*
Y272050D03*
Y398810D03*
Y423810D03*
G54D14*
X3000Y8494D03*
Y28494D03*
Y48494D03*
Y68494D03*
Y88494D03*
Y108494D03*
Y128494D03*
Y148494D03*
Y168494D03*
Y188494D03*
Y208494D03*
Y228494D03*
Y248494D03*
Y268494D03*
Y288494D03*
Y308494D03*
Y342126D03*
Y362126D03*
Y382126D03*
Y402126D03*
Y422126D03*
Y442126D03*
X16626Y195848D03*
X19129D03*
Y193048D03*
X16626D03*
X19129Y204248D03*
X17000Y208017D03*
X16626Y198648D03*
Y201448D03*
X19129Y198648D03*
Y201448D03*
X16626Y204248D03*
X6200Y312900D03*
X13827Y325310D03*
X21250Y206220D03*
X36599Y189016D03*
X37360Y194050D03*
X37823Y198346D03*
X48035Y191535D03*
X47714Y212227D03*
X48940Y204871D03*
X52155Y121218D03*
X60112Y113992D03*
X222402Y169197D03*
X238188Y225852D03*
X228739Y213254D03*
X250749Y159748D03*
X244020Y235518D03*
X244487Y229002D03*
X268510Y179088D03*
X301120Y226421D03*
Y229810D03*
X302687Y275497D03*
X296938Y325700D03*
X311301Y182385D03*
X309521Y226397D03*
Y229786D03*
X314969Y456527D03*
X329297Y134594D03*
Y129890D03*
X321276Y134532D03*
X321349Y130044D03*
X326323Y226349D03*
X317922Y226373D03*
X326323Y229738D03*
X317922Y229762D03*
X373480Y-210223D03*
X370965D03*
Y-206970D03*
X376406Y-206985D03*
X373480Y-206970D03*
X372271Y-213263D03*
X373480Y18049D03*
X370965D03*
X372271Y15009D03*
X370965Y21302D03*
X376406Y21287D03*
X373480Y21302D03*
X372271Y384281D03*
X376406Y390559D03*
X373480Y387321D03*
Y390574D03*
X370965Y387321D03*
Y390574D03*
X383057Y-213263D03*
X381848Y-206970D03*
X384363D03*
Y-210223D03*
X381848D03*
X378922Y-206970D03*
X392081Y-115285D03*
Y-112032D03*
X383057Y15009D03*
X384363Y18049D03*
X381848D03*
Y21302D03*
X384363D03*
X378922D03*
X391950Y214106D03*
Y217359D03*
X378922Y390574D03*
X381848D03*
Y387321D03*
X384363Y390574D03*
Y387321D03*
X383057Y384281D03*
X391950Y412378D03*
Y415631D03*
X394596Y-115285D03*
X393387Y-118325D03*
X404173D03*
X405479Y-115285D03*
X402964D03*
X397522Y-112047D03*
X394596Y-112032D03*
X402964D03*
X405479D03*
X400038D03*
X393357Y211066D03*
X403857D03*
X394450Y217359D03*
Y214106D03*
X396950Y217359D03*
X399450Y217344D03*
X402450Y217359D03*
X404950D03*
X402450Y214106D03*
X404950D03*
X394450Y415631D03*
Y412378D03*
X396950Y415631D03*
X399450Y415616D03*
X393357Y409338D03*
X402450Y415631D03*
X404950D03*
X402450Y412378D03*
X404950D03*
X403857Y409338D03*
X414143Y211066D03*
X415550Y214106D03*
Y217359D03*
X413050D03*
Y214106D03*
X410550Y217359D03*
X408050Y217344D03*
X415550Y412378D03*
Y415631D03*
X413050D03*
Y412378D03*
X410550Y415631D03*
X408050Y415616D03*
X414143Y409338D03*
G54D22*
X23723Y123791D03*
Y120791D03*
X32223Y123791D03*
Y120791D03*
X40723Y123791D03*
Y120791D03*
X49223Y123791D03*
Y121291D03*
X38300Y109200D03*
X60411Y130200D03*
X57470Y426544D03*
X51535D03*
X56482Y450344D03*
X62600Y450700D03*
X71035Y426543D03*
X76770D03*
X142780Y266830D03*
X142500Y345800D03*
X175359Y153286D03*
X178346Y162898D03*
Y172347D03*
Y184945D03*
X181194Y294074D03*
X169669Y399419D03*
X197243Y156599D03*
X187794Y159748D03*
X197243Y178646D03*
X187794Y181795D03*
X197243Y191244D03*
Y197506D03*
Y203805D03*
X184645Y206955D03*
X197243Y200655D03*
Y219553D03*
X194094Y232151D03*
X184645D03*
X185725Y307320D03*
X209842Y156599D03*
X203542Y169197D03*
X212991D03*
X206692D03*
X212991Y181795D03*
X206692Y178646D03*
X209842Y181795D03*
X203542Y191244D03*
X206692D03*
X209842Y184945D03*
X200393Y191244D03*
X203542Y197506D03*
X209842D03*
X203542Y210104D03*
X212991Y206955D03*
Y210104D03*
X209842D03*
X200393D03*
X203542Y200655D03*
X209842D03*
X212991Y219553D03*
X205130Y282000D03*
X204207Y278200D03*
X225552Y156599D03*
X219253Y178646D03*
X225552D03*
Y184945D03*
X219253Y232151D03*
X215600Y316800D03*
X228702Y169197D03*
X231851Y191244D03*
X241300D03*
X235001Y184945D03*
X228702Y191244D03*
X235001Y200655D03*
Y206955D03*
Y219553D03*
X241300Y213254D03*
X238150Y219553D03*
X228702D03*
X238630Y235654D03*
X231851Y232151D03*
X241300D03*
X255492Y152905D03*
X244450Y156599D03*
X253898Y172347D03*
Y178646D03*
X247599Y181795D03*
Y175496D03*
X253898Y191244D03*
Y184945D03*
X247599Y197506D03*
Y188095D03*
Y203805D03*
X253898Y206955D03*
Y200655D03*
X257048Y219553D03*
X250749D03*
Y232151D03*
X257048Y235301D03*
X263294Y153366D03*
X263030Y150846D03*
X268391Y207262D03*
X269391Y214593D03*
X280744Y142070D03*
X283248Y142046D03*
X287725Y363473D03*
X293693Y152232D03*
X290889Y152318D03*
X297372Y196616D03*
X308500Y382100D03*
X339800Y154911D03*
Y159911D03*
Y165911D03*
Y169911D03*
Y176911D03*
Y179911D03*
Y185911D03*
Y189911D03*
X337004Y202113D03*
Y206113D03*
Y210113D03*
G54D37*
X262880Y178977D03*
X308460Y214178D03*
G54D41*
X441000Y-454000D03*
X451000D03*
X441000Y-333400D03*
X451000D03*
X441000Y2000D03*
X451000D03*
X441000Y116000D03*
X451000D03*
G54D15*
X17716Y18465D03*
X45276D03*
X264173Y20040D03*
X291733D03*
X309055Y18465D03*
X336615D03*
G54D31*
X143118Y44803D03*
X194851D03*
G54D32*
X153237Y58583D03*
X165048Y52677D03*
X155205D03*
X161111Y58583D03*
X168985D03*
X172922Y52677D03*
X176859Y58583D03*
X184733D03*
G54D40*
X441000Y-444000D03*
X451000D03*
Y-355000D03*
X441000D03*
Y-323400D03*
X451000D03*
Y-245000D03*
X441000D03*
X451000Y-215000D03*
X441000D03*
Y-136600D03*
X451000D03*
Y-107000D03*
X441000D03*
Y-18000D03*
X451000D03*
X441000Y12000D03*
X451000D03*
Y96000D03*
X441000D03*
Y126000D03*
X451000D03*
Y200000D03*
X441000D03*
X451000Y230000D03*
X441000D03*
Y304000D03*
X451000D03*
Y336000D03*
X441000D03*
Y420000D03*
X451000D03*
G54D44*
X441000Y-126600D03*
X451000D03*
X441000Y-8000D03*
X451000D03*
X441000Y314000D03*
X451000D03*
X441000Y430000D03*
X451000D03*
G54D18*
X24016Y89331D03*
X330315D03*
G54D11*
X-61709Y56192D03*
X-51709D03*
X-61100Y250316D03*
X-61000Y382816D03*
X-51100Y250316D03*
X-51000Y382816D03*
X-35000Y56184D03*
X-25000D03*
X-25100Y250316D03*
X-35100D03*
X-36000Y418816D03*
X-26000D03*
G54D26*
X65945Y297776D03*
G54D36*
X236220Y424016D03*
X301181D03*
G54D33*
X144685Y297776D03*
G54D17*
X22047Y46417D03*
X333466D03*
G54D30*
X105316Y213343D03*
G54D24*
X23819Y349154D03*
X95709Y52244D03*
G54D34*
X182764Y52677D03*
G54D35*
X221142Y24764D03*
G54D10*
X-56709Y43008D03*
X-30000Y43000D03*
G54D29*
X105315Y186571D03*
G54D21*
X27300Y68200D03*
X340639Y432809D03*
G54D20*
X18000Y240900D03*
Y237900D03*
Y249900D03*
Y246900D03*
Y243900D03*
X15688Y259063D03*
X21135Y236587D03*
X21205Y232767D03*
X21135Y240667D03*
Y243737D03*
X24690Y246467D03*
Y251967D03*
X21135Y246837D03*
X21035Y249937D03*
X24690Y249267D03*
X22237Y311481D03*
Y308592D03*
X30638Y311957D03*
Y309068D03*
X22692Y466518D03*
X47440Y308691D03*
X39039Y309044D03*
Y311933D03*
X47440Y312080D03*
X63300Y237600D03*
X68375Y144100D03*
X70580Y167179D03*
X65800Y260875D03*
X81600Y241500D03*
X87500Y237300D03*
X84000Y261375D03*
X103500Y240619D03*
X113590Y245170D03*
X143300Y396400D03*
X146600Y410600D03*
X172550Y398690D03*
X200274Y410960D03*
X225552Y197543D03*
X225441Y282267D03*
X257048Y225890D03*
X292361Y197970D03*
X314985Y397639D03*
Y394639D03*
X332470Y397092D03*
Y394092D03*
X331646Y466536D03*
X339101Y117328D03*
Y121128D03*
X337842Y128533D03*
X334723Y226349D03*
Y229738D03*
X351331Y20788D03*
Y40788D03*
Y60788D03*
Y80788D03*
Y100788D03*
Y120788D03*
Y140788D03*
Y160788D03*
Y180788D03*
Y200788D03*
Y220788D03*
Y240788D03*
Y260788D03*
Y280788D03*
Y300788D03*
Y357531D03*
Y377531D03*
Y397531D03*
Y417531D03*
Y437531D03*
X373420Y-447134D03*
X370905D03*
Y-443881D03*
X373420D03*
X376346Y-447134D03*
X372211Y-440841D03*
X372183Y-162569D03*
X373392Y-168862D03*
X370877D03*
Y-165609D03*
X373392D03*
X376318Y-168862D03*
X373420Y59410D03*
X370905D03*
Y62663D03*
X373420D03*
X376346Y59410D03*
X372211Y65703D03*
X391993Y-473196D03*
Y-469943D03*
X381788Y-443881D03*
X384303D03*
Y-447134D03*
X378862Y-447119D03*
X381788Y-447134D03*
X382997Y-440841D03*
X381760Y-165609D03*
X384275D03*
Y-168862D03*
X378834Y-168847D03*
X381760Y-168862D03*
X382969Y-162569D03*
X391950Y-74043D03*
Y-70790D03*
X381788Y62663D03*
X384303D03*
Y59410D03*
X378862Y59425D03*
X381788Y59410D03*
X382997Y65703D03*
X391950Y255229D03*
Y258482D03*
X405391Y-473196D03*
X399950Y-473181D03*
X402876Y-473196D03*
X394508D03*
X397434D03*
X402876Y-469943D03*
X405391D03*
X404085Y-466903D03*
X393299D03*
X394508Y-469943D03*
X399450Y-74028D03*
X394450Y-74043D03*
Y-70790D03*
X396950Y-74043D03*
X405050D03*
X402550D03*
X405050Y-70790D03*
X402550D03*
X393357Y-67750D03*
X403643D03*
X394450Y255229D03*
X396950D03*
X399450Y255244D03*
X405050Y255229D03*
X402550D03*
X394450Y258482D03*
X393357Y261522D03*
X405050Y258482D03*
X402550D03*
X403643Y261522D03*
X415550Y-70790D03*
Y-74043D03*
X413050D03*
Y-70790D03*
X410550Y-74043D03*
X408050Y-74028D03*
X414143Y-67750D03*
X415550Y255229D03*
X413050D03*
X410550D03*
X408050Y255244D03*
X415550Y258482D03*
X413050D03*
X414143Y261522D03*
G54D38*
X285482Y190187D03*
G54D16*
X9407Y10554D03*
X12900Y105500D03*
X17000Y211541D03*
Y215713D03*
Y219288D03*
X8300Y314700D03*
X22218Y3000D03*
X27323Y25842D03*
X31920Y186610D03*
X25811Y319400D03*
X32000Y326300D03*
X23535Y329990D03*
X34300Y375000D03*
X33100Y392100D03*
X20225Y447671D03*
X42218Y3000D03*
X35044Y35751D03*
X43926Y62248D03*
X45276Y98488D03*
X47294Y184491D03*
X39567Y243133D03*
X40500Y236900D03*
X41574Y255937D03*
X44500Y355500D03*
X38200Y364855D03*
X36600Y408600D03*
X40848Y448440D03*
X62218Y3000D03*
X53000Y41500D03*
X59425Y53075D03*
X50508Y57459D03*
X57500Y75500D03*
X60000D03*
X53267Y109094D03*
X57141Y209341D03*
X59900Y199900D03*
X52000Y230400D03*
X62500Y272500D03*
X60561Y314843D03*
X62458Y390481D03*
X59097Y433502D03*
X63563Y460100D03*
X56476D03*
X76500Y66500D03*
X65928Y76500D03*
X72044Y132312D03*
X71970Y135893D03*
X69195Y135799D03*
X69285Y132321D03*
X67126Y128100D03*
X68335Y141369D03*
X68434Y149506D03*
X68432Y152147D03*
X65301Y187762D03*
X67486Y186414D03*
X72000Y235925D03*
X65801Y253145D03*
X76500Y270700D03*
X74000Y270800D03*
X76284Y280470D03*
X75300Y305150D03*
X69500Y308700D03*
X64567Y306665D03*
X73000Y323400D03*
X68757Y352724D03*
X71906Y355873D03*
X75056Y359023D03*
X65607Y349574D03*
X75056Y377883D03*
X68757Y384182D03*
X65607Y387332D03*
X75018Y381033D03*
X69057Y419700D03*
X78800Y423800D03*
X66297Y433002D03*
X70650Y460100D03*
X77500D03*
X82218Y3000D03*
X91700Y66500D03*
X86500Y75000D03*
X88500Y128000D03*
X81800Y188500D03*
X90900Y222850D03*
X85672Y283985D03*
X81864Y297900D03*
X85600Y298100D03*
X82200Y308700D03*
X82022Y303350D03*
X84126Y311790D03*
X79600Y312000D03*
X85500Y323400D03*
X85600Y335000D03*
X87617Y365322D03*
Y371584D03*
X81355Y365322D03*
Y371584D03*
X86300Y397600D03*
X92001Y450402D03*
X82256Y445577D03*
X85276Y445550D03*
X84823Y460100D03*
X91909Y458275D03*
X102218Y3000D03*
X95400Y66500D03*
X98000Y75500D03*
X108727Y99153D03*
X100000Y98500D03*
X105916Y109952D03*
X101230Y127010D03*
X96400Y137475D03*
X97440Y283590D03*
X105000Y311900D03*
X96457Y323194D03*
X97608Y335534D03*
X100215Y352724D03*
X103383Y349556D03*
X93916Y359023D03*
X97066Y355873D03*
X103383Y387350D03*
X100215Y384182D03*
X93916Y377883D03*
X97066Y381033D03*
X103400Y420000D03*
X95280Y412500D03*
X97156Y450437D03*
X94560Y443287D03*
X100225Y443127D03*
X98996Y458275D03*
X106083D03*
X122218Y3000D03*
X111000Y44600D03*
X122500Y58000D03*
X116560Y88651D03*
X120726Y105000D03*
X115200Y98200D03*
X120626Y123500D03*
X112000D03*
X116200Y115100D03*
X119060Y199695D03*
X118300Y237500D03*
X121720Y265330D03*
X111177Y293471D03*
X118009Y313810D03*
Y311200D03*
X115000Y369500D03*
X127900Y45000D03*
X129575Y57375D03*
X129328Y122500D03*
X126575Y111416D03*
X131700Y131000D03*
X133500Y149385D03*
X124500Y167100D03*
X126300Y176575D03*
X135000Y206900D03*
X128900Y255898D03*
X131216Y280187D03*
X124016Y313784D03*
X135462Y313727D03*
X133100Y358900D03*
X133640Y390524D03*
X124287Y406262D03*
X127300Y392600D03*
X129900Y415583D03*
X138500Y457250D03*
X142218Y3000D03*
X147947Y9800D03*
X146800Y79000D03*
X140869Y89055D03*
X141700Y96929D03*
X140869Y104803D03*
Y120551D03*
Y112677D03*
X142000Y146000D03*
X148400Y155765D03*
X153134Y178572D03*
X146390Y224040D03*
X146000Y216350D03*
X141954Y224274D03*
X142300Y216300D03*
X152400Y293400D03*
X150293Y315493D03*
X140700Y370252D03*
X140300Y395100D03*
X152100Y425700D03*
X145365Y426050D03*
X149041Y458750D03*
X162218Y3000D03*
X165700Y11100D03*
X166719Y75874D03*
X168297Y93976D03*
X164429Y93991D03*
X158873Y93976D03*
X166500Y96400D03*
X158420Y116610D03*
X159700Y112000D03*
X161237Y185815D03*
X161240Y190477D03*
X166361Y209794D03*
X166308Y225189D03*
X155800Y234700D03*
X163690Y268610D03*
X164790Y341100D03*
X163800Y356800D03*
X164318Y389102D03*
X157282D03*
X156900Y385700D03*
X154000Y414750D03*
X165194Y428688D03*
X160852Y460118D03*
X182218Y3000D03*
X173853Y93991D03*
X182925Y84300D03*
X180333Y114292D03*
X178346Y200655D03*
Y213254D03*
Y225852D03*
X174079Y234604D03*
X174400Y249136D03*
X173880Y312430D03*
X182372Y325961D03*
X169200Y349400D03*
X180350Y368650D03*
X177082Y387402D03*
X182750Y426750D03*
X187272Y84472D03*
X191312Y84512D03*
X190200Y100500D03*
X198281Y101286D03*
X187360Y132425D03*
X187794Y213254D03*
X196827Y240349D03*
X185897Y249936D03*
X191583Y261363D03*
X189228Y280655D03*
X190922Y350990D03*
X184118Y387402D03*
X185875Y415051D03*
X189600Y459800D03*
X202218Y3000D03*
X207700Y59100D03*
X213100Y69300D03*
X209500Y92326D03*
X211800Y93870D03*
X209824Y106122D03*
X203600Y117000D03*
X203970Y125500D03*
X211200Y140513D03*
X200393Y169197D03*
X203542Y232151D03*
X198990Y247811D03*
X211265Y267300D03*
X207220Y301180D03*
X207750Y366500D03*
X208360Y384890D03*
X203180Y416371D03*
X211865Y444520D03*
X200000Y455800D03*
X209300Y457700D03*
X222218Y3000D03*
X227547Y74275D03*
X219600Y74000D03*
X215800Y69300D03*
X218600D03*
X224958Y107236D03*
X221500Y125100D03*
X217697Y174852D03*
X219290Y191207D03*
X222402Y206955D03*
Y213254D03*
X223672Y290735D03*
X213610Y308800D03*
X223160Y362600D03*
X222225Y407650D03*
X216725D03*
X218085Y444520D03*
X222200Y458700D03*
X215000Y458600D03*
X242218Y3000D03*
X233000Y47100D03*
X230800Y57613D03*
X239347Y79457D03*
X237280Y107510D03*
X229000Y101000D03*
X242812Y117501D03*
X242800Y132200D03*
X231100Y125600D03*
X235001Y166047D03*
X238150Y169197D03*
X232773Y269532D03*
X228800Y302700D03*
X241400Y328100D03*
X233468Y341046D03*
X233300Y356890D03*
X233600Y371500D03*
X233800Y390118D03*
X228230Y390390D03*
X228200Y459100D03*
X248359Y46559D03*
X248700Y75900D03*
X255750Y77350D03*
X250900Y90900D03*
X254397Y103697D03*
X244987Y103528D03*
X251113Y102919D03*
X252300Y107664D03*
X245391Y99589D03*
X252374Y132159D03*
X244450Y159748D03*
X253388Y273655D03*
X246200Y299700D03*
X243410Y381323D03*
X245300Y445800D03*
X262218Y3000D03*
X267022Y12166D03*
X269095Y34625D03*
X260970Y42441D03*
X268675Y74400D03*
X267168Y93768D03*
X260132D03*
X259759Y103651D03*
X259500Y101100D03*
X268435Y121476D03*
X260269Y207358D03*
X261269Y214657D03*
X266200Y300500D03*
X262930Y325300D03*
X259420Y345930D03*
X265922Y354238D03*
X272100Y396300D03*
X265100Y424000D03*
X266300Y435900D03*
X271500Y446800D03*
X269534Y459061D03*
X282218Y3000D03*
X277000Y41982D03*
X282440Y51941D03*
X274219Y51641D03*
X286000Y67975D03*
X274400Y90019D03*
X279200Y114100D03*
X274500Y131629D03*
X279600Y131400D03*
X285980Y163487D03*
X278155Y176085D03*
X286105Y172936D03*
Y182385D03*
Y197989D03*
Y201139D03*
X286000Y242100D03*
X281889Y287636D03*
X276155Y329999D03*
X276100Y375900D03*
Y381500D03*
X284614Y387136D03*
X281300Y419300D03*
X278200Y408700D03*
X277563Y460028D03*
X283707Y459398D03*
X302218Y3000D03*
X300600Y10591D03*
X288856Y12166D03*
X295402Y48051D03*
X290245Y46978D03*
X300856Y104059D03*
X301151Y108649D03*
X301936Y135797D03*
X294200Y128800D03*
X301507Y195435D03*
X289091Y204331D03*
X289254Y210587D03*
Y213737D03*
X301500Y326500D03*
X298748Y390118D03*
X297399Y397382D03*
X290800Y438300D03*
X291689Y453912D03*
Y456912D03*
Y459912D03*
X313977Y33400D03*
X303575Y54516D03*
X304436Y135897D03*
X307500Y125635D03*
X308008Y163487D03*
X311158Y185534D03*
X314307Y191690D03*
X311158Y194839D03*
Y204288D03*
X314307Y207438D03*
X303940Y212664D03*
X311158Y201139D03*
Y213737D03*
X307500Y256500D03*
X312114Y288439D03*
X315810Y293450D03*
X312315Y293207D03*
X317430Y295665D03*
X314820Y296128D03*
X314201Y302361D03*
X314180Y299440D03*
X303077Y297519D03*
X314132Y310178D03*
X314170Y307020D03*
X309500Y315000D03*
X304000Y305000D03*
X311000Y320500D03*
X315075Y366500D03*
X312226Y382766D03*
X322218Y3000D03*
X319175Y60200D03*
X322600Y76100D03*
X331881Y108593D03*
Y104577D03*
Y112608D03*
X320239Y151075D03*
X323384Y157378D03*
X331405Y157411D03*
X323384Y165378D03*
Y161378D03*
Y169378D03*
Y173378D03*
Y177378D03*
X331405Y177411D03*
Y187411D03*
Y192411D03*
X319601Y201140D03*
X317670Y291430D03*
X330900Y314700D03*
X325038Y356890D03*
X325320Y390118D03*
X325200Y383900D03*
X342218Y3000D03*
X337375Y76600D03*
X342900Y66100D03*
X333278Y151129D03*
X337083Y197000D03*
X336312Y286352D03*
X339700Y295900D03*
X342604Y318773D03*
X335700Y376400D03*
X335500Y363200D03*
X334600Y383300D03*
X334112Y447668D03*
X349290Y337646D03*
X374975Y-435380D03*
X374666Y-218571D03*
X374947Y-157108D03*
X374666Y9701D03*
X374975Y71164D03*
X374666Y378973D03*
X380602Y-435533D03*
X380293Y-218724D03*
X380574Y-157261D03*
X380293Y9548D03*
X380602Y71011D03*
X380293Y378820D03*
X396063Y-461442D03*
X401690Y-461595D03*
X401409Y-123786D03*
X395782Y-123633D03*
G54D42*
X451000Y-345000D03*
X441000D03*
X451000Y-235000D03*
X441000D03*
X451000Y106000D03*
X441000D03*
X451000Y210000D03*
X441000D03*
G54D43*
X451000Y-225000D03*
X441000D03*
X451000Y-117000D03*
X441000D03*
X451000Y220000D03*
X441000D03*
X451000Y326000D03*
X441000D03*
G54D27*
X58654Y290605D03*
X104575Y62369D03*
Y67581D03*
G54D13*
X-30100Y263500D03*
G54D12*
X-56100D03*
X-56000Y396000D03*
X-31000Y432000D03*
%LPC*%
G75*
G54D45*
G01X2010999Y-388000D02*
Y1475775D01*
X-407000D01*
Y-386798D01*
Y-755294D01*
Y-793716D01*
X-368578D01*
X1942346D01*
X2010999D01*
Y-725063D01*
Y-388000D01*
G01X-53307Y-609436D02*
Y-684436D01*
X446693D01*
Y-609436D01*
X-53307D01*
G01X-41307Y-674436D02*
Y-679436D01*
G01X-42764Y-674436D02*
X-39850D01*
G01X-34940Y-679436D02*
X-37474D01*
Y-674436D01*
X-34940D01*
G01X-35954Y-676853D02*
X-37474D01*
G01X-32374Y-674436D02*
Y-679436D01*
X-29840D01*
G01X-26007Y-679603D02*
X-26134Y-679519D01*
Y-679353D01*
X-26007Y-679269D01*
X-25880Y-679353D01*
Y-679519D01*
X-26007Y-679603D01*
G01Y-677353D02*
X-26134Y-677269D01*
Y-677103D01*
X-26007Y-677019D01*
X-25880Y-677103D01*
Y-677269D01*
X-26007Y-677353D01*
G01X-21224Y-681103D02*
X-21857Y-680269D01*
X-22174Y-679436D01*
Y-676103D01*
X-21857Y-675269D01*
X-21224Y-674436D01*
G01X-15807D02*
X-16314Y-674603D01*
X-16694Y-675019D01*
X-16947Y-675519D01*
X-17137Y-676186D01*
X-17200Y-676936D01*
X-17137Y-677686D01*
X-16947Y-678353D01*
X-16694Y-678853D01*
X-16314Y-679269D01*
X-15807Y-679436D01*
X-15300Y-679269D01*
X-14920Y-678853D01*
X-14667Y-678353D01*
X-14477Y-677686D01*
X-14414Y-676936D01*
X-14477Y-676186D01*
X-14667Y-675519D01*
X-14920Y-675019D01*
X-15300Y-674603D01*
X-15807Y-674436D01*
G01X-12100Y-678436D02*
X-11720Y-679019D01*
X-11214Y-679353D01*
X-10644Y-679436D01*
X-10137Y-679353D01*
X-9630Y-678936D01*
X-9314Y-678436D01*
X-9250Y-677936D01*
X-9377Y-677353D01*
X-9820Y-676936D01*
X-10264Y-676769D01*
X-10834D01*
G01X-10264D02*
X-9884Y-676519D01*
X-9567Y-676103D01*
X-9440Y-675603D01*
X-9567Y-675103D01*
X-9884Y-674686D01*
X-10454Y-674436D01*
X-11024Y-674519D01*
X-11594Y-674853D01*
G01X-5290Y-681103D02*
X-4657Y-680269D01*
X-4340Y-679436D01*
Y-676103D01*
X-4657Y-675269D01*
X-5290Y-674436D01*
G01X-1900Y-678436D02*
X-1520Y-679019D01*
X-1014Y-679353D01*
X-444Y-679436D01*
X63Y-679353D01*
X570Y-678936D01*
X886Y-678436D01*
X950Y-677936D01*
X823Y-677353D01*
X380Y-676936D01*
X-64Y-676769D01*
X-634D01*
G01X-64D02*
X316Y-676519D01*
X633Y-676103D01*
X760Y-675603D01*
X633Y-675103D01*
X316Y-674686D01*
X-254Y-674436D01*
X-824Y-674519D01*
X-1394Y-674853D01*
G01X3390Y-675269D02*
X3770Y-674769D01*
X4213Y-674519D01*
X4720Y-674436D01*
X5353Y-674603D01*
X5796Y-675019D01*
X5923Y-675519D01*
X5860Y-676019D01*
X5606Y-676436D01*
X4340Y-677269D01*
X3770Y-677853D01*
X3390Y-678686D01*
X3263Y-679436D01*
X5923D01*
G01X9566D02*
X9693Y-678353D01*
X9883Y-677436D01*
X10136Y-676603D01*
X10453Y-675686D01*
X10960Y-674436D01*
X8426D01*
G01X13970Y-677769D02*
X15616D01*
G01X18690Y-675269D02*
X19070Y-674769D01*
X19513Y-674519D01*
X20020Y-674436D01*
X20653Y-674603D01*
X21096Y-675019D01*
X21223Y-675519D01*
X21160Y-676019D01*
X20906Y-676436D01*
X19640Y-677269D01*
X19070Y-677853D01*
X18690Y-678686D01*
X18563Y-679436D01*
X21223D01*
G01X23600Y-678436D02*
X23980Y-679019D01*
X24486Y-679353D01*
X25056Y-679436D01*
X25563Y-679353D01*
X26070Y-678936D01*
X26386Y-678436D01*
X26450Y-677936D01*
X26323Y-677353D01*
X25880Y-676936D01*
X25436Y-676769D01*
X24866D01*
G01X25436D02*
X25816Y-676519D01*
X26133Y-676103D01*
X26260Y-675603D01*
X26133Y-675103D01*
X25816Y-674686D01*
X25246Y-674436D01*
X24676Y-674519D01*
X24106Y-674853D01*
G01X30853Y-679436D02*
Y-674436D01*
X28510Y-678019D01*
X31676D01*
G01X33800Y-678686D02*
X34180Y-679103D01*
X34623Y-679353D01*
X35193Y-679436D01*
X35763Y-679269D01*
X36206Y-678936D01*
X36523Y-678353D01*
X36586Y-677686D01*
X36460Y-677019D01*
X36143Y-676603D01*
X35700Y-676269D01*
X35256Y-676186D01*
X34813Y-676269D01*
X34243Y-676603D01*
X34433Y-674436D01*
X36143D01*
G01X44190Y-679436D02*
Y-674436D01*
X46596D01*
G01X45710Y-676853D02*
X44190D01*
G01X48910Y-679436D02*
X50493Y-674436D01*
X52076Y-679436D01*
G01X51506Y-677686D02*
X49480D01*
G01X54263Y-679436D02*
X56923Y-674436D01*
G01X54263D02*
X56923Y-679436D01*
G01X60693Y-679603D02*
X60566Y-679519D01*
Y-679353D01*
X60693Y-679269D01*
X60820Y-679353D01*
Y-679519D01*
X60693Y-679603D01*
G01Y-677353D02*
X60566Y-677269D01*
Y-677103D01*
X60693Y-677019D01*
X60820Y-677103D01*
Y-677269D01*
X60693Y-677353D01*
G01X65476Y-681103D02*
X64843Y-680269D01*
X64526Y-679436D01*
Y-676103D01*
X64843Y-675269D01*
X65476Y-674436D01*
G01X70893D02*
X70386Y-674603D01*
X70006Y-675019D01*
X69753Y-675519D01*
X69563Y-676186D01*
X69500Y-676936D01*
X69563Y-677686D01*
X69753Y-678353D01*
X70006Y-678853D01*
X70386Y-679269D01*
X70893Y-679436D01*
X71400Y-679269D01*
X71780Y-678853D01*
X72033Y-678353D01*
X72223Y-677686D01*
X72286Y-676936D01*
X72223Y-676186D01*
X72033Y-675519D01*
X71780Y-675019D01*
X71400Y-674603D01*
X70893Y-674436D01*
G01X74600Y-678436D02*
X74980Y-679019D01*
X75486Y-679353D01*
X76056Y-679436D01*
X76563Y-679353D01*
X77070Y-678936D01*
X77386Y-678436D01*
X77450Y-677936D01*
X77323Y-677353D01*
X76880Y-676936D01*
X76436Y-676769D01*
X75866D01*
G01X76436D02*
X76816Y-676519D01*
X77133Y-676103D01*
X77260Y-675603D01*
X77133Y-675103D01*
X76816Y-674686D01*
X76246Y-674436D01*
X75676Y-674519D01*
X75106Y-674853D01*
G01X81410Y-681103D02*
X82043Y-680269D01*
X82360Y-679436D01*
Y-676103D01*
X82043Y-675269D01*
X81410Y-674436D01*
G01X84800Y-678436D02*
X85180Y-679019D01*
X85686Y-679353D01*
X86256Y-679436D01*
X86763Y-679353D01*
X87270Y-678936D01*
X87586Y-678436D01*
X87650Y-677936D01*
X87523Y-677353D01*
X87080Y-676936D01*
X86636Y-676769D01*
X86066D01*
G01X86636D02*
X87016Y-676519D01*
X87333Y-676103D01*
X87460Y-675603D01*
X87333Y-675103D01*
X87016Y-674686D01*
X86446Y-674436D01*
X85876Y-674519D01*
X85306Y-674853D01*
G01X90216Y-678853D02*
X90660Y-679269D01*
X91166Y-679436D01*
X91673Y-679269D01*
X92116Y-678769D01*
X92433Y-678019D01*
X92560Y-677269D01*
Y-676353D01*
X92433Y-675603D01*
X92116Y-674936D01*
X91736Y-674603D01*
X91293Y-674436D01*
X90786Y-674603D01*
X90406Y-674936D01*
X90153Y-675436D01*
X90026Y-676103D01*
X90153Y-676686D01*
X90470Y-677269D01*
X90850Y-677603D01*
X91293Y-677686D01*
X91800Y-677519D01*
X92180Y-677103D01*
X92560Y-676353D01*
G01X96266Y-679436D02*
X96393Y-678353D01*
X96583Y-677436D01*
X96836Y-676603D01*
X97153Y-675686D01*
X97660Y-674436D01*
X95126D01*
G01X100670Y-677769D02*
X102316D01*
G01X105200Y-678436D02*
X105580Y-679019D01*
X106086Y-679353D01*
X106656Y-679436D01*
X107163Y-679353D01*
X107670Y-678936D01*
X107986Y-678436D01*
X108050Y-677936D01*
X107923Y-677353D01*
X107480Y-676936D01*
X107036Y-676769D01*
X106466D01*
G01X107036D02*
X107416Y-676519D01*
X107733Y-676103D01*
X107860Y-675603D01*
X107733Y-675103D01*
X107416Y-674686D01*
X106846Y-674436D01*
X106276Y-674519D01*
X105706Y-674853D01*
G01X110490Y-677353D02*
X110933Y-676769D01*
X111313Y-676436D01*
X111820Y-676269D01*
X112263Y-676436D01*
X112580Y-676769D01*
X112833Y-677269D01*
X112896Y-677853D01*
X112833Y-678353D01*
X112580Y-678853D01*
X112200Y-679269D01*
X111756Y-679436D01*
X111250Y-679269D01*
X110806Y-678769D01*
X110553Y-678019D01*
X110490Y-677186D01*
X110616Y-676103D01*
X110806Y-675519D01*
X111123Y-674936D01*
X111566Y-674519D01*
X112010Y-674436D01*
X112453Y-674603D01*
X112770Y-675019D01*
G01X116793Y-679436D02*
Y-674436D01*
X116033Y-675436D01*
G01Y-679436D02*
X117553D01*
G01X122653D02*
Y-674436D01*
X120310Y-678019D01*
X123476D01*
G01X141693Y-609436D02*
Y-684436D01*
G01Y-659436D02*
X244693D01*
Y-634436D01*
G01X141693D02*
X244693D01*
G01X246693Y-609436D02*
Y-684436D01*
G01X244693Y-609436D02*
Y-684436D01*
G01X252200Y-669436D02*
Y-664436D01*
X253466D01*
X253973Y-664686D01*
X254353Y-665019D01*
X254670Y-665519D01*
X254923Y-666103D01*
X254986Y-666936D01*
X254923Y-667769D01*
X254670Y-668353D01*
X254353Y-668853D01*
X253973Y-669186D01*
X253466Y-669436D01*
X252200D01*
G01X257110D02*
X258693Y-664436D01*
X260276Y-669436D01*
G01X259706Y-667686D02*
X257680D01*
G01X263793Y-664436D02*
Y-669436D01*
G01X262336Y-664436D02*
X265250D01*
G01X270160Y-669436D02*
X267626D01*
Y-664436D01*
X270160D01*
G01X269146Y-666853D02*
X267626D01*
G01X273993Y-669603D02*
X273866Y-669519D01*
Y-669353D01*
X273993Y-669269D01*
X274120Y-669353D01*
Y-669519D01*
X273993Y-669603D01*
G01Y-667353D02*
X273866Y-667269D01*
Y-667103D01*
X273993Y-667019D01*
X274120Y-667103D01*
Y-667269D01*
X273993Y-667353D01*
G01X246693Y-659436D02*
X446693D01*
G01X252326Y-644436D02*
Y-639436D01*
X253846D01*
X254353Y-639686D01*
X254733Y-640269D01*
X254860Y-640936D01*
X254733Y-641603D01*
X254416Y-642103D01*
X253846Y-642353D01*
X252326D01*
G01X257553Y-644603D02*
X259833Y-639436D01*
G01X262336Y-644436D02*
Y-639436D01*
X265250Y-644436D01*
Y-639436D01*
G01X268893Y-644603D02*
X268766Y-644519D01*
Y-644353D01*
X268893Y-644269D01*
X269020Y-644353D01*
Y-644519D01*
X268893Y-644603D01*
G01Y-642353D02*
X268766Y-642269D01*
Y-642103D01*
X268893Y-642019D01*
X269020Y-642103D01*
Y-642269D01*
X268893Y-642353D01*
G01X246693Y-634436D02*
X446693D01*
G01X252326Y-619436D02*
Y-614436D01*
X253846D01*
X254353Y-614686D01*
X254733Y-615269D01*
X254860Y-615936D01*
X254733Y-616603D01*
X254416Y-617103D01*
X253846Y-617353D01*
X252326D01*
G01X257426Y-619436D02*
Y-614436D01*
X259010D01*
X259516Y-614686D01*
X259833Y-615019D01*
X259960Y-615686D01*
X259833Y-616353D01*
X259453Y-616769D01*
X259010Y-617019D01*
X257426D01*
G01X259010D02*
X259960Y-619436D01*
G01X263793D02*
X263286Y-619353D01*
X262843Y-619019D01*
X262463Y-618519D01*
X262210Y-617936D01*
X262083Y-617269D01*
Y-616603D01*
X262210Y-615936D01*
X262463Y-615353D01*
X262843Y-614853D01*
X263286Y-614519D01*
X263793Y-614436D01*
X264300Y-614519D01*
X264743Y-614853D01*
X265123Y-615353D01*
X265376Y-615936D01*
X265503Y-616603D01*
Y-617269D01*
X265376Y-617936D01*
X265123Y-618519D01*
X264743Y-619019D01*
X264300Y-619353D01*
X263793Y-619436D01*
G01X267626Y-618436D02*
X267943Y-618936D01*
X268323Y-619269D01*
X268766Y-619436D01*
X269273Y-619269D01*
X269653Y-618936D01*
X270033Y-618436D01*
X270160Y-617769D01*
Y-614436D01*
G01X275260Y-619436D02*
X272726D01*
Y-614436D01*
X275260D01*
G01X274246Y-616853D02*
X272726D01*
G01X280486Y-614853D02*
X280106Y-614603D01*
X279663Y-614436D01*
X279156D01*
X278586Y-614686D01*
X278143Y-615103D01*
X277826Y-615603D01*
X277573Y-616436D01*
X277510Y-617186D01*
X277636Y-617936D01*
X277826Y-618436D01*
X278206Y-618936D01*
X278650Y-619269D01*
X279093Y-619436D01*
X279536D01*
X279980Y-619269D01*
X280360Y-619019D01*
X280676Y-618686D01*
G01X284193Y-614436D02*
Y-619436D01*
G01X282736Y-614436D02*
X285650D01*
G01X289293Y-619603D02*
X289166Y-619519D01*
Y-619353D01*
X289293Y-619269D01*
X289420Y-619353D01*
Y-619519D01*
X289293Y-619603D01*
G01Y-617353D02*
X289166Y-617269D01*
Y-617103D01*
X289293Y-617019D01*
X289420Y-617103D01*
Y-617269D01*
X289293Y-617353D01*
G01X361693Y-659436D02*
Y-684436D01*
G01X364326Y-661936D02*
Y-666936D01*
X366860D01*
G01X369933Y-661936D02*
X371453D01*
G01X370693D02*
Y-666936D01*
G01X369933D02*
X371453D01*
G01X376300Y-664269D02*
X376553Y-664019D01*
X376743Y-663603D01*
X376870Y-663019D01*
X376743Y-662519D01*
X376490Y-662186D01*
X376046Y-661936D01*
X374336D01*
Y-666936D01*
X376426D01*
X376870Y-666603D01*
X377123Y-666103D01*
X377250Y-665519D01*
X377123Y-664936D01*
X376743Y-664436D01*
X376300Y-664269D01*
X374336D01*
G01X380893Y-667103D02*
X380766Y-667019D01*
Y-666853D01*
X380893Y-666769D01*
X381020Y-666853D01*
Y-667019D01*
X380893Y-667103D01*
G01Y-664853D02*
X380766Y-664769D01*
Y-664603D01*
X380893Y-664519D01*
X381020Y-664603D01*
Y-664769D01*
X380893Y-664853D01*
G01X404693Y-659436D02*
Y-684436D01*
G01Y-634436D02*
Y-659436D01*
G01X412706Y-687603D02*
X412813Y-687478D01*
X412893Y-687269D01*
X412946Y-686978D01*
X412893Y-686728D01*
X412786Y-686561D01*
X412600Y-686436D01*
X411880D01*
Y-688936D01*
X412760D01*
X412946Y-688769D01*
X413053Y-688519D01*
X413106Y-688228D01*
X413053Y-687936D01*
X412893Y-687686D01*
X412706Y-687603D01*
X411880D01*
G01X415173Y-688936D02*
Y-687269D01*
G01Y-687561D02*
X415066Y-687394D01*
X414906Y-687311D01*
X414720Y-687269D01*
X414533Y-687353D01*
X414373Y-687519D01*
X414266Y-687769D01*
X414213Y-688103D01*
X414266Y-688436D01*
X414373Y-688686D01*
X414533Y-688853D01*
X414720Y-688936D01*
X414906Y-688894D01*
X415066Y-688769D01*
X415173Y-688603D01*
G01X416493Y-688644D02*
X416626Y-688811D01*
X416813Y-688936D01*
X416973D01*
X417133Y-688853D01*
X417240Y-688728D01*
X417293Y-688561D01*
X417266Y-688311D01*
X417160Y-688186D01*
X416680Y-687936D01*
X416573Y-687644D01*
X416626Y-687436D01*
X416733Y-687311D01*
X416893Y-687269D01*
X417053Y-687311D01*
X417213Y-687436D01*
G01X418693Y-687811D02*
X419546D01*
X419466Y-687519D01*
X419333Y-687353D01*
X419146Y-687269D01*
X418960Y-687311D01*
X418800Y-687436D01*
X418693Y-687728D01*
X418640Y-687978D01*
Y-688228D01*
X418693Y-688478D01*
X418826Y-688728D01*
X418986Y-688894D01*
X419173Y-688936D01*
X419360Y-688853D01*
X419546Y-688603D01*
G01X420813Y-688936D02*
Y-686436D01*
G01Y-687686D02*
X420946Y-687436D01*
X421106Y-687311D01*
X421266Y-687269D01*
X421506Y-687353D01*
X421666Y-687519D01*
X421773Y-687811D01*
Y-688144D01*
X421720Y-688478D01*
X421613Y-688728D01*
X421426Y-688894D01*
X421266Y-688936D01*
X421106Y-688894D01*
X420946Y-688769D01*
X420813Y-688561D01*
G01X423493Y-688936D02*
X423333Y-688894D01*
X423173Y-688728D01*
X423066Y-688436D01*
X423013Y-688103D01*
X423066Y-687769D01*
X423173Y-687478D01*
X423333Y-687311D01*
X423493Y-687269D01*
X423653Y-687311D01*
X423813Y-687478D01*
X423920Y-687769D01*
X423946Y-688103D01*
X423920Y-688436D01*
X423813Y-688728D01*
X423653Y-688894D01*
X423493Y-688936D01*
G01X426173D02*
Y-687269D01*
G01Y-687561D02*
X426066Y-687394D01*
X425906Y-687311D01*
X425720Y-687269D01*
X425533Y-687353D01*
X425373Y-687519D01*
X425266Y-687769D01*
X425213Y-688103D01*
X425266Y-688436D01*
X425373Y-688686D01*
X425533Y-688853D01*
X425720Y-688936D01*
X425906Y-688894D01*
X426066Y-688769D01*
X426173Y-688603D01*
G01X427520Y-688936D02*
Y-687269D01*
G01Y-687603D02*
X427653Y-687436D01*
X427786Y-687311D01*
X427973Y-687269D01*
X428106Y-687311D01*
X428266Y-687436D01*
G01X430573Y-686436D02*
Y-688936D01*
G01Y-688561D02*
X430466Y-688769D01*
X430306Y-688894D01*
X430120Y-688936D01*
X429906Y-688853D01*
X429746Y-688644D01*
X429640Y-688394D01*
X429613Y-688103D01*
X429640Y-687811D01*
X429746Y-687561D01*
X429906Y-687353D01*
X430120Y-687269D01*
X430306Y-687311D01*
X430440Y-687394D01*
X430573Y-687561D01*
G01X433960Y-688936D02*
Y-686436D01*
X434626D01*
X434840Y-686561D01*
X434973Y-686728D01*
X435026Y-687061D01*
X434973Y-687394D01*
X434813Y-687603D01*
X434626Y-687728D01*
X433960D01*
G01X434626D02*
X435026Y-688936D01*
G01X436293Y-687811D02*
X437146D01*
X437066Y-687519D01*
X436933Y-687353D01*
X436746Y-687269D01*
X436560Y-687311D01*
X436400Y-687436D01*
X436293Y-687728D01*
X436240Y-687978D01*
Y-688228D01*
X436293Y-688478D01*
X436426Y-688728D01*
X436586Y-688894D01*
X436773Y-688936D01*
X436960Y-688853D01*
X437146Y-688603D01*
G01X438413Y-687269D02*
X438893Y-688936D01*
X439373Y-687269D01*
G01X441093Y-689019D02*
X441040Y-688978D01*
Y-688894D01*
X441093Y-688853D01*
X441146Y-688894D01*
Y-688978D01*
X441093Y-689019D01*
G01X443613Y-688936D02*
Y-686436D01*
X442626Y-688228D01*
X443960D01*
G01X444826Y-688936D02*
X445493Y-686436D01*
X446160Y-688936D01*
G01X445920Y-688061D02*
X445066D01*
G01X408593Y-661936D02*
Y-666936D01*
G01X407136Y-661936D02*
X410050D01*
G01X413693Y-666936D02*
X413313Y-666853D01*
X412933Y-666519D01*
X412680Y-665936D01*
X412553Y-665269D01*
X412680Y-664603D01*
X412933Y-664019D01*
X413313Y-663686D01*
X413693Y-663603D01*
X414073Y-663686D01*
X414453Y-664019D01*
X414706Y-664603D01*
X414770Y-665269D01*
X414706Y-665936D01*
X414453Y-666519D01*
X414073Y-666853D01*
X413693Y-666936D01*
G01X418793D02*
X418413Y-666853D01*
X418033Y-666519D01*
X417780Y-665936D01*
X417653Y-665269D01*
X417780Y-664603D01*
X418033Y-664019D01*
X418413Y-663686D01*
X418793Y-663603D01*
X419173Y-663686D01*
X419553Y-664019D01*
X419806Y-664603D01*
X419870Y-665269D01*
X419806Y-665936D01*
X419553Y-666519D01*
X419173Y-666853D01*
X418793Y-666936D01*
G01X423893D02*
Y-661936D01*
G01X428993Y-667103D02*
X428866Y-667019D01*
Y-666853D01*
X428993Y-666769D01*
X429120Y-666853D01*
Y-667019D01*
X428993Y-667103D01*
G01Y-664853D02*
X428866Y-664769D01*
Y-664603D01*
X428993Y-664519D01*
X429120Y-664603D01*
Y-664769D01*
X428993Y-664853D01*
G01X407326Y-641936D02*
Y-636936D01*
X408910D01*
X409416Y-637186D01*
X409733Y-637519D01*
X409860Y-638186D01*
X409733Y-638853D01*
X409353Y-639269D01*
X408910Y-639519D01*
X407326D01*
G01X408910D02*
X409860Y-641936D01*
G01X414960D02*
X412426D01*
Y-636936D01*
X414960D01*
G01X413946Y-639353D02*
X412426D01*
G01X417210Y-636936D02*
X418793Y-641936D01*
X420376Y-636936D01*
G01X423893Y-642103D02*
X423766Y-642019D01*
Y-641853D01*
X423893Y-641769D01*
X424020Y-641853D01*
Y-642019D01*
X423893Y-642103D01*
G01Y-639853D02*
X423766Y-639769D01*
Y-639603D01*
X423893Y-639519D01*
X424020Y-639603D01*
Y-639769D01*
X423893Y-639853D01*
G01X2010999Y-388000D02*
Y1475775D01*
X-407000D01*
Y-386798D01*
Y-755294D01*
Y-793716D01*
X-368578D01*
X1942346D01*
X2010999D01*
Y-725063D01*
Y-388000D01*
G01X-42602Y-671096D02*
X-41975Y-671621D01*
X-41270Y-671936D01*
X-40644D01*
X-40017Y-671621D01*
X-39547Y-671096D01*
X-39312Y-670361D01*
X-39469Y-669626D01*
X-39860Y-668996D01*
X-40565Y-668576D01*
X-41505Y-668366D01*
X-42054Y-667946D01*
X-42289Y-667211D01*
X-42132Y-666476D01*
X-41740Y-665951D01*
X-41192Y-665636D01*
X-40644D01*
X-40095Y-665846D01*
X-39625Y-666371D01*
G01X-36302Y-671936D02*
Y-665636D01*
G01X-33012D02*
Y-671936D01*
G01Y-668786D02*
X-36302D01*
G01X-29297Y-665636D02*
X-27417D01*
G01X-28357D02*
Y-671936D01*
G01X-29297D02*
X-27417D01*
G01X-20490D02*
X-23624D01*
Y-665636D01*
X-20490D01*
G01X-21744Y-668681D02*
X-23624D01*
G01X-17559Y-671936D02*
Y-665636D01*
X-13955Y-671936D01*
Y-665636D01*
G01X-9614Y-673091D02*
X-9300Y-671726D01*
G01X-3157Y-665636D02*
Y-671936D01*
G01X-4959Y-665636D02*
X-1355D01*
G01X1185Y-671936D02*
X3143Y-665636D01*
X5101Y-671936D01*
G01X4396Y-669731D02*
X1890D01*
G01X8503Y-665636D02*
X10383D01*
G01X9443D02*
Y-671936D01*
G01X8503D02*
X10383D01*
G01X13393Y-665636D02*
X14490Y-671936D01*
X15743Y-665636D01*
X16996Y-671936D01*
X18093Y-665636D01*
G01X20085Y-671936D02*
X22043Y-665636D01*
X24001Y-671936D01*
G01X23296Y-669731D02*
X20790D01*
G01X26541Y-671936D02*
Y-665636D01*
X30145Y-671936D01*
Y-665636D01*
G01X39376Y-671936D02*
Y-665636D01*
X41335D01*
X41961Y-665951D01*
X42353Y-666371D01*
X42510Y-667211D01*
X42353Y-668051D01*
X41883Y-668576D01*
X41335Y-668891D01*
X39376D01*
G01X41335D02*
X42510Y-671936D01*
G01X47243Y-672146D02*
X47086Y-672041D01*
Y-671831D01*
X47243Y-671726D01*
X47400Y-671831D01*
Y-672041D01*
X47243Y-672146D01*
G01X53543Y-671936D02*
X52916Y-671831D01*
X52368Y-671411D01*
X51898Y-670781D01*
X51585Y-670046D01*
X51428Y-669206D01*
Y-668366D01*
X51585Y-667526D01*
X51898Y-666791D01*
X52368Y-666161D01*
X52916Y-665741D01*
X53543Y-665636D01*
X54170Y-665741D01*
X54718Y-666161D01*
X55188Y-666791D01*
X55501Y-667526D01*
X55658Y-668366D01*
Y-669206D01*
X55501Y-670046D01*
X55188Y-670781D01*
X54718Y-671411D01*
X54170Y-671831D01*
X53543Y-671936D01*
G01X59843Y-672146D02*
X59686Y-672041D01*
Y-671831D01*
X59843Y-671726D01*
X60000Y-671831D01*
Y-672041D01*
X59843Y-672146D01*
G01X67866Y-666161D02*
X67396Y-665846D01*
X66848Y-665636D01*
X66221D01*
X65516Y-665951D01*
X64968Y-666476D01*
X64576Y-667106D01*
X64263Y-668156D01*
X64185Y-669101D01*
X64341Y-670046D01*
X64576Y-670676D01*
X65046Y-671306D01*
X65595Y-671726D01*
X66143Y-671936D01*
X66691D01*
X67240Y-671726D01*
X67710Y-671411D01*
X68101Y-670991D01*
G01X72443Y-672146D02*
X72286Y-672041D01*
Y-671831D01*
X72443Y-671726D01*
X72600Y-671831D01*
Y-672041D01*
X72443Y-672146D01*
G01X-42680Y-661936D02*
Y-655636D01*
G01X-39704D02*
X-42680Y-659521D01*
G01X-39234Y-661936D02*
X-41349Y-657736D01*
G01X-36380Y-655636D02*
Y-660151D01*
X-36067Y-661096D01*
X-35440Y-661726D01*
X-34657Y-661936D01*
X-33874Y-661726D01*
X-33247Y-661096D01*
X-32934Y-660151D01*
Y-655636D01*
G01X-26790Y-661936D02*
X-29924D01*
Y-655636D01*
X-26790D01*
G01X-28044Y-658681D02*
X-29924D01*
G01X-22997Y-655636D02*
X-21117D01*
G01X-22057D02*
Y-661936D01*
G01X-22997D02*
X-21117D01*
G01X-11102Y-661096D02*
X-10475Y-661621D01*
X-9770Y-661936D01*
X-9144D01*
X-8517Y-661621D01*
X-8047Y-661096D01*
X-7812Y-660361D01*
X-7969Y-659626D01*
X-8360Y-658996D01*
X-9065Y-658576D01*
X-10005Y-658366D01*
X-10554Y-657946D01*
X-10789Y-657211D01*
X-10632Y-656476D01*
X-10240Y-655951D01*
X-9692Y-655636D01*
X-9144D01*
X-8595Y-655846D01*
X-8125Y-656371D01*
G01X-4802Y-661936D02*
Y-655636D01*
G01X-1512D02*
Y-661936D01*
G01Y-658786D02*
X-4802D01*
G01X1185Y-661936D02*
X3143Y-655636D01*
X5101Y-661936D01*
G01X4396Y-659731D02*
X1890D01*
G01X7641Y-661936D02*
Y-655636D01*
X11245Y-661936D01*
Y-655636D01*
G01X20398Y-661936D02*
Y-655636D01*
G01X23688D02*
Y-661936D01*
G01Y-658786D02*
X20398D01*
G01X26698Y-661096D02*
X27325Y-661621D01*
X28030Y-661936D01*
X28656D01*
X29283Y-661621D01*
X29753Y-661096D01*
X29988Y-660361D01*
X29831Y-659626D01*
X29440Y-658996D01*
X28735Y-658576D01*
X27795Y-658366D01*
X27246Y-657946D01*
X27011Y-657211D01*
X27168Y-656476D01*
X27560Y-655951D01*
X28108Y-655636D01*
X28656D01*
X29205Y-655846D01*
X29675Y-656371D01*
G01X33703Y-655636D02*
X35583D01*
G01X34643D02*
Y-661936D01*
G01X33703D02*
X35583D01*
G01X38985D02*
X40943Y-655636D01*
X42901Y-661936D01*
G01X42196Y-659731D02*
X39690D01*
G01X45441Y-661936D02*
Y-655636D01*
X49045Y-661936D01*
Y-655636D01*
G01X54013Y-658786D02*
X55580D01*
Y-660676D01*
X55110Y-661306D01*
X54561Y-661726D01*
X53778Y-661936D01*
X52995Y-661726D01*
X52446Y-661306D01*
X51976Y-660676D01*
X51663Y-659941D01*
X51506Y-659101D01*
Y-658366D01*
X51663Y-657736D01*
X51976Y-657001D01*
X52446Y-656371D01*
X52916Y-655951D01*
X53543Y-655636D01*
X54091D01*
X54718Y-655846D01*
X55188Y-656266D01*
G01X59686Y-663091D02*
X60000Y-661726D01*
G01X66143Y-655636D02*
Y-661936D01*
G01X64341Y-655636D02*
X67945D01*
G01X70485Y-661936D02*
X72443Y-655636D01*
X74401Y-661936D01*
G01X73696Y-659731D02*
X71190D01*
G01X78743Y-661936D02*
X78116Y-661831D01*
X77568Y-661411D01*
X77098Y-660781D01*
X76785Y-660046D01*
X76628Y-659206D01*
Y-658366D01*
X76785Y-657526D01*
X77098Y-656791D01*
X77568Y-656161D01*
X78116Y-655741D01*
X78743Y-655636D01*
X79370Y-655741D01*
X79918Y-656161D01*
X80388Y-656791D01*
X80701Y-657526D01*
X80858Y-658366D01*
Y-659206D01*
X80701Y-660046D01*
X80388Y-660781D01*
X79918Y-661411D01*
X79370Y-661831D01*
X78743Y-661936D01*
G01X91343D02*
Y-659101D01*
X89776Y-655636D01*
G01X92910D02*
X91343Y-659101D01*
G01X95920Y-655636D02*
Y-660151D01*
X96233Y-661096D01*
X96860Y-661726D01*
X97643Y-661936D01*
X98426Y-661726D01*
X99053Y-661096D01*
X99366Y-660151D01*
Y-655636D01*
G01X101985Y-661936D02*
X103943Y-655636D01*
X105901Y-661936D01*
G01X105196Y-659731D02*
X102690D01*
G01X108441Y-661936D02*
Y-655636D01*
X112045Y-661936D01*
Y-655636D01*
G01X-42759Y-651936D02*
Y-645636D01*
X-39155Y-651936D01*
Y-645636D01*
G01X-34657Y-651936D02*
X-35284Y-651831D01*
X-35832Y-651411D01*
X-36302Y-650781D01*
X-36615Y-650046D01*
X-36772Y-649206D01*
Y-648366D01*
X-36615Y-647526D01*
X-36302Y-646791D01*
X-35832Y-646161D01*
X-35284Y-645741D01*
X-34657Y-645636D01*
X-34030Y-645741D01*
X-33482Y-646161D01*
X-33012Y-646791D01*
X-32699Y-647526D01*
X-32542Y-648366D01*
Y-649206D01*
X-32699Y-650046D01*
X-33012Y-650781D01*
X-33482Y-651411D01*
X-34030Y-651831D01*
X-34657Y-651936D01*
G01X-28357Y-652146D02*
X-28514Y-652041D01*
Y-651831D01*
X-28357Y-651726D01*
X-28200Y-651831D01*
Y-652041D01*
X-28357Y-652146D01*
G01X-22057Y-651936D02*
Y-645636D01*
X-22997Y-646896D01*
G01Y-651936D02*
X-21117D01*
G01X-15757D02*
X-15209Y-651831D01*
X-14582Y-651516D01*
X-14190Y-650991D01*
X-14034Y-650256D01*
X-14190Y-649521D01*
X-14660Y-648891D01*
X-15365Y-648576D01*
X-16149D01*
X-16619Y-648366D01*
X-17010Y-647841D01*
X-17167Y-647106D01*
X-16932Y-646371D01*
X-16384Y-645846D01*
X-15757Y-645636D01*
X-15130Y-645846D01*
X-14582Y-646371D01*
X-14347Y-647106D01*
X-14504Y-647841D01*
X-14895Y-648366D01*
X-15365Y-648576D01*
X-16149D01*
X-16854Y-648891D01*
X-17324Y-649521D01*
X-17480Y-650256D01*
X-17324Y-650991D01*
X-16932Y-651516D01*
X-16305Y-651831D01*
X-15757Y-651936D01*
G01X-9457D02*
X-8909Y-651831D01*
X-8282Y-651516D01*
X-7890Y-650991D01*
X-7734Y-650256D01*
X-7890Y-649521D01*
X-8360Y-648891D01*
X-9065Y-648576D01*
X-9849D01*
X-10319Y-648366D01*
X-10710Y-647841D01*
X-10867Y-647106D01*
X-10632Y-646371D01*
X-10084Y-645846D01*
X-9457Y-645636D01*
X-8830Y-645846D01*
X-8282Y-646371D01*
X-8047Y-647106D01*
X-8204Y-647841D01*
X-8595Y-648366D01*
X-9065Y-648576D01*
X-9849D01*
X-10554Y-648891D01*
X-11024Y-649521D01*
X-11180Y-650256D01*
X-11024Y-650991D01*
X-10632Y-651516D01*
X-10005Y-651831D01*
X-9457Y-651936D01*
G01X-3314Y-653091D02*
X-3000Y-651726D01*
G01X793Y-645636D02*
X1890Y-651936D01*
X3143Y-645636D01*
X4396Y-651936D01*
X5493Y-645636D01*
G01X11010Y-651936D02*
X7876D01*
Y-645636D01*
X11010D01*
G01X9756Y-648681D02*
X7876D01*
G01X13941Y-651936D02*
Y-645636D01*
X17545Y-651936D01*
Y-645636D01*
G01X26698Y-651936D02*
Y-645636D01*
G01X29988D02*
Y-651936D01*
G01Y-648786D02*
X26698D01*
G01X32293Y-645636D02*
X33390Y-651936D01*
X34643Y-645636D01*
X35896Y-651936D01*
X36993Y-645636D01*
G01X38985Y-651936D02*
X40943Y-645636D01*
X42901Y-651936D01*
G01X42196Y-649731D02*
X39690D01*
G01X52055Y-646686D02*
X52525Y-646056D01*
X53073Y-645741D01*
X53700Y-645636D01*
X54483Y-645846D01*
X55031Y-646371D01*
X55188Y-647001D01*
X55110Y-647631D01*
X54796Y-648156D01*
X53230Y-649206D01*
X52525Y-649941D01*
X52055Y-650991D01*
X51898Y-651936D01*
X55188D01*
G01X58041D02*
Y-645636D01*
X61645Y-651936D01*
Y-645636D01*
G01X64420Y-651936D02*
Y-645636D01*
X65986D01*
X66613Y-645951D01*
X67083Y-646371D01*
X67475Y-647001D01*
X67788Y-647736D01*
X67866Y-648786D01*
X67788Y-649836D01*
X67475Y-650571D01*
X67083Y-651201D01*
X66613Y-651621D01*
X65986Y-651936D01*
X64420D01*
G01X77176D02*
Y-645636D01*
X79135D01*
X79761Y-645951D01*
X80153Y-646371D01*
X80310Y-647211D01*
X80153Y-648051D01*
X79683Y-648576D01*
X79135Y-648891D01*
X77176D01*
G01X79135D02*
X80310Y-651936D01*
G01X83320D02*
Y-645636D01*
X84886D01*
X85513Y-645951D01*
X85983Y-646371D01*
X86375Y-647001D01*
X86688Y-647736D01*
X86766Y-648786D01*
X86688Y-649836D01*
X86375Y-650571D01*
X85983Y-651201D01*
X85513Y-651621D01*
X84886Y-651936D01*
X83320D01*
G01X91343Y-652146D02*
X91186Y-652041D01*
Y-651831D01*
X91343Y-651726D01*
X91500Y-651831D01*
Y-652041D01*
X91343Y-652146D01*
G01X-18657Y-639236D02*
X-21177Y-638819D01*
X-23382Y-637153D01*
X-25272Y-634653D01*
X-26532Y-631736D01*
X-27162Y-628403D01*
Y-625069D01*
X-26532Y-621736D01*
X-25272Y-618819D01*
X-23382Y-616320D01*
X-21177Y-614653D01*
X-18657Y-614236D01*
X-16137Y-614653D01*
X-13932Y-616320D01*
X-12042Y-618819D01*
X-10782Y-621736D01*
X-10152Y-625069D01*
Y-628403D01*
X-10782Y-631736D01*
X-12042Y-634653D01*
X-13932Y-637153D01*
X-16137Y-638819D01*
X-18657Y-639236D01*
G01X-16137Y-632569D02*
X-12357Y-639236D01*
G01X1188Y-622570D02*
Y-634236D01*
X2448Y-637153D01*
X4338Y-638819D01*
X6543Y-639236D01*
X8748Y-638819D01*
X10638Y-637153D01*
X11898Y-634236D01*
G01Y-639236D02*
Y-622570D01*
G01X37413Y-639236D02*
Y-622570D01*
G01Y-625486D02*
X36153Y-623820D01*
X34263Y-622986D01*
X32058Y-622570D01*
X29853Y-623403D01*
X27963Y-625069D01*
X26703Y-627570D01*
X26073Y-630903D01*
X26703Y-634236D01*
X27963Y-636737D01*
X29853Y-638403D01*
X32058Y-639236D01*
X34263Y-638819D01*
X36153Y-637570D01*
X37413Y-635903D01*
G01X51588Y-639236D02*
Y-622570D01*
G01Y-626736D02*
X52848Y-624653D01*
X54738Y-622986D01*
X57258Y-622570D01*
X59463Y-622986D01*
X61353Y-624653D01*
X62298Y-627570D01*
Y-639236D01*
G01X82143Y-614236D02*
Y-639236D01*
G01X77733Y-622570D02*
X86553D01*
G01X113013Y-639236D02*
Y-622570D01*
G01Y-625486D02*
X111753Y-623820D01*
X109863Y-622986D01*
X107658Y-622570D01*
X105453Y-623403D01*
X103563Y-625069D01*
X102303Y-627570D01*
X101673Y-630903D01*
X102303Y-634236D01*
X103563Y-636737D01*
X105453Y-638403D01*
X107658Y-639236D01*
X109863Y-638819D01*
X111753Y-637570D01*
X113013Y-635903D01*
G01X152693Y-618936D02*
Y-626936D01*
X156693D01*
G01X164493D02*
Y-621603D01*
G01Y-622536D02*
X164093Y-622003D01*
X163493Y-621736D01*
X162793Y-621603D01*
X162093Y-621869D01*
X161493Y-622403D01*
X161093Y-623203D01*
X160893Y-624269D01*
X161093Y-625336D01*
X161493Y-626136D01*
X162093Y-626669D01*
X162793Y-626936D01*
X163493Y-626803D01*
X164093Y-626403D01*
X164493Y-625870D01*
G01X168593Y-629336D02*
X169193Y-629603D01*
X169993Y-629336D01*
X170493Y-628803D01*
X170893Y-628136D01*
X171493Y-626003D01*
X172793Y-621603D01*
G01X169593D02*
X171493Y-626003D01*
G01X177193Y-623336D02*
X180393D01*
X180093Y-622403D01*
X179593Y-621869D01*
X178893Y-621603D01*
X178193Y-621736D01*
X177593Y-622136D01*
X177193Y-623069D01*
X176993Y-623870D01*
Y-624669D01*
X177193Y-625469D01*
X177693Y-626269D01*
X178293Y-626803D01*
X178993Y-626936D01*
X179693Y-626669D01*
X180393Y-625870D01*
G01X185293Y-626936D02*
Y-621603D01*
G01Y-622669D02*
X185793Y-622136D01*
X186293Y-621736D01*
X186993Y-621603D01*
X187493Y-621736D01*
X188093Y-622136D01*
G01X173993Y-676936D02*
Y-668936D01*
G01X177793D02*
X173993Y-673870D01*
G01X178393Y-676936D02*
X175693Y-671603D01*
G01X185993Y-676936D02*
Y-671603D01*
G01Y-672536D02*
X185593Y-672003D01*
X184993Y-671736D01*
X184293Y-671603D01*
X183593Y-671869D01*
X182993Y-672403D01*
X182593Y-673203D01*
X182393Y-674269D01*
X182593Y-675336D01*
X182993Y-676136D01*
X183593Y-676669D01*
X184293Y-676936D01*
X184993Y-676803D01*
X185593Y-676403D01*
X185993Y-675870D01*
G01X192193Y-671603D02*
Y-676936D01*
G01Y-669469D02*
X191993Y-669336D01*
Y-669069D01*
X192193Y-668936D01*
X192393Y-669069D01*
Y-669336D01*
X192193Y-669469D01*
G01X184293Y-647936D02*
X186293D01*
Y-650336D01*
X185693Y-651136D01*
X184993Y-651669D01*
X183993Y-651936D01*
X182993Y-651669D01*
X182293Y-651136D01*
X181693Y-650336D01*
X181293Y-649403D01*
X181093Y-648336D01*
Y-647403D01*
X181293Y-646603D01*
X181693Y-645669D01*
X182293Y-644869D01*
X182893Y-644336D01*
X183693Y-643936D01*
X184393D01*
X185193Y-644203D01*
X185793Y-644736D01*
G01X189393Y-651936D02*
Y-643936D01*
X193993Y-651936D01*
Y-643936D01*
G01X197493Y-651936D02*
Y-643936D01*
X199493D01*
X200293Y-644336D01*
X200893Y-644869D01*
X201393Y-645669D01*
X201793Y-646603D01*
X201893Y-647936D01*
X201793Y-649269D01*
X201393Y-650203D01*
X200893Y-651003D01*
X200293Y-651536D01*
X199493Y-651936D01*
X197493D01*
G01X205793Y-645269D02*
X206393Y-644469D01*
X207093Y-644069D01*
X207893Y-643936D01*
X208893Y-644203D01*
X209593Y-644869D01*
X209793Y-645669D01*
X209693Y-646470D01*
X209293Y-647136D01*
X207293Y-648469D01*
X206393Y-649403D01*
X205793Y-650736D01*
X205593Y-651936D01*
X209793D01*
G01X204493Y-626003D02*
X205193Y-626669D01*
X205993Y-626936D01*
X206793Y-626669D01*
X207493Y-625870D01*
X207993Y-624669D01*
X208193Y-623469D01*
Y-622003D01*
X207993Y-620803D01*
X207493Y-619736D01*
X206893Y-619203D01*
X206193Y-618936D01*
X205393Y-619203D01*
X204793Y-619736D01*
X204393Y-620536D01*
X204193Y-621603D01*
X204393Y-622536D01*
X204893Y-623469D01*
X205493Y-624003D01*
X206193Y-624136D01*
X206993Y-623870D01*
X207593Y-623203D01*
X208193Y-622003D01*
G01X279293Y-670269D02*
X279893Y-669469D01*
X280593Y-669069D01*
X281393Y-668936D01*
X282393Y-669203D01*
X283093Y-669869D01*
X283293Y-670669D01*
X283193Y-671470D01*
X282793Y-672136D01*
X280793Y-673469D01*
X279893Y-674403D01*
X279293Y-675736D01*
X279093Y-676936D01*
X283293D01*
G01X289193Y-668936D02*
X288393Y-669203D01*
X287793Y-669869D01*
X287393Y-670669D01*
X287093Y-671736D01*
X286993Y-672936D01*
X287093Y-674136D01*
X287393Y-675203D01*
X287793Y-676003D01*
X288393Y-676669D01*
X289193Y-676936D01*
X289993Y-676669D01*
X290593Y-676003D01*
X290993Y-675203D01*
X291293Y-674136D01*
X291393Y-672936D01*
X291293Y-671736D01*
X290993Y-670669D01*
X290593Y-669869D01*
X289993Y-669203D01*
X289193Y-668936D01*
G01X295293Y-670269D02*
X295893Y-669469D01*
X296593Y-669069D01*
X297393Y-668936D01*
X298393Y-669203D01*
X299093Y-669869D01*
X299293Y-670669D01*
X299193Y-671470D01*
X298793Y-672136D01*
X296793Y-673469D01*
X295893Y-674403D01*
X295293Y-675736D01*
X295093Y-676936D01*
X299293D01*
G01X303293Y-670269D02*
X303893Y-669469D01*
X304593Y-669069D01*
X305393Y-668936D01*
X306393Y-669203D01*
X307093Y-669869D01*
X307293Y-670669D01*
X307193Y-671470D01*
X306793Y-672136D01*
X304793Y-673469D01*
X303893Y-674403D01*
X303293Y-675736D01*
X303093Y-676936D01*
X307293D01*
G01X311393Y-677203D02*
X314993Y-668936D01*
G01X321193Y-676936D02*
Y-668936D01*
X319993Y-670536D01*
G01Y-676936D02*
X322393D01*
G01X327293Y-670269D02*
X327893Y-669469D01*
X328593Y-669069D01*
X329393Y-668936D01*
X330393Y-669203D01*
X331093Y-669869D01*
X331293Y-670669D01*
X331193Y-671470D01*
X330793Y-672136D01*
X328793Y-673469D01*
X327893Y-674403D01*
X327293Y-675736D01*
X327093Y-676936D01*
X331293D01*
G01X335393Y-677203D02*
X338993Y-668936D01*
G01X345193D02*
X344393Y-669203D01*
X343793Y-669869D01*
X343393Y-670669D01*
X343093Y-671736D01*
X342993Y-672936D01*
X343093Y-674136D01*
X343393Y-675203D01*
X343793Y-676003D01*
X344393Y-676669D01*
X345193Y-676936D01*
X345993Y-676669D01*
X346593Y-676003D01*
X346993Y-675203D01*
X347293Y-674136D01*
X347393Y-672936D01*
X347293Y-671736D01*
X346993Y-670669D01*
X346593Y-669869D01*
X345993Y-669203D01*
X345193Y-668936D01*
G01X351493Y-676003D02*
X352193Y-676669D01*
X352993Y-676936D01*
X353793Y-676669D01*
X354493Y-675870D01*
X354993Y-674669D01*
X355193Y-673469D01*
Y-672003D01*
X354993Y-670803D01*
X354493Y-669736D01*
X353893Y-669203D01*
X353193Y-668936D01*
X352393Y-669203D01*
X351793Y-669736D01*
X351393Y-670536D01*
X351193Y-671603D01*
X351393Y-672536D01*
X351893Y-673469D01*
X352493Y-674003D01*
X353193Y-674136D01*
X353993Y-673870D01*
X354593Y-673203D01*
X355193Y-672003D01*
G01X278993Y-651936D02*
Y-643936D01*
X280993D01*
X281793Y-644336D01*
X282393Y-644869D01*
X282893Y-645669D01*
X283293Y-646603D01*
X283393Y-647936D01*
X283293Y-649269D01*
X282893Y-650203D01*
X282393Y-651003D01*
X281793Y-651536D01*
X280993Y-651936D01*
X278993D01*
G01X286693D02*
X289193Y-643936D01*
X291693Y-651936D01*
G01X290793Y-649136D02*
X287593D01*
G01X297193Y-643936D02*
X296393Y-644203D01*
X295793Y-644869D01*
X295393Y-645669D01*
X295093Y-646736D01*
X294993Y-647936D01*
X295093Y-649136D01*
X295393Y-650203D01*
X295793Y-651003D01*
X296393Y-651669D01*
X297193Y-651936D01*
X297993Y-651669D01*
X298593Y-651003D01*
X298993Y-650203D01*
X299293Y-649136D01*
X299393Y-647936D01*
X299293Y-646736D01*
X298993Y-645669D01*
X298593Y-644869D01*
X297993Y-644203D01*
X297193Y-643936D01*
G01X303293Y-651936D02*
Y-643936D01*
X307093D01*
G01X305693Y-647803D02*
X303293D01*
G01X313193Y-643936D02*
X312393Y-644203D01*
X311793Y-644869D01*
X311393Y-645669D01*
X311093Y-646736D01*
X310993Y-647936D01*
X311093Y-649136D01*
X311393Y-650203D01*
X311793Y-651003D01*
X312393Y-651669D01*
X313193Y-651936D01*
X313993Y-651669D01*
X314593Y-651003D01*
X314993Y-650203D01*
X315293Y-649136D01*
X315393Y-647936D01*
X315293Y-646736D01*
X314993Y-645669D01*
X314593Y-644869D01*
X313993Y-644203D01*
X313193Y-643936D01*
G01X321193D02*
Y-651936D01*
G01X318893Y-643936D02*
X323493D01*
G01X326593Y-651936D02*
Y-643936D01*
X329193Y-650603D01*
X331793Y-643936D01*
Y-651936D01*
G01X334993D02*
Y-643936D01*
X336993D01*
X337793Y-644336D01*
X338393Y-644869D01*
X338893Y-645669D01*
X339293Y-646603D01*
X339393Y-647936D01*
X339293Y-649269D01*
X338893Y-650203D01*
X338393Y-651003D01*
X337793Y-651536D01*
X336993Y-651936D01*
X334993D01*
G01X347393Y-644603D02*
X346793Y-644203D01*
X346093Y-643936D01*
X345293D01*
X344393Y-644336D01*
X343693Y-645003D01*
X343193Y-645803D01*
X342793Y-647136D01*
X342693Y-648336D01*
X342893Y-649536D01*
X343193Y-650336D01*
X343793Y-651136D01*
X344493Y-651669D01*
X345193Y-651936D01*
X345893D01*
X346593Y-651669D01*
X347193Y-651269D01*
X347693Y-650736D01*
G01X350993Y-651936D02*
Y-643936D01*
X352993D01*
X353793Y-644336D01*
X354393Y-644869D01*
X354893Y-645669D01*
X355293Y-646603D01*
X355393Y-647936D01*
X355293Y-649269D01*
X354893Y-650203D01*
X354393Y-651003D01*
X353793Y-651536D01*
X352993Y-651936D01*
X350993D01*
G01X361193Y-643936D02*
X360393Y-644203D01*
X359793Y-644869D01*
X359393Y-645669D01*
X359093Y-646736D01*
X358993Y-647936D01*
X359093Y-649136D01*
X359393Y-650203D01*
X359793Y-651003D01*
X360393Y-651669D01*
X361193Y-651936D01*
X361993Y-651669D01*
X362593Y-651003D01*
X362993Y-650203D01*
X363293Y-649136D01*
X363393Y-647936D01*
X363293Y-646736D01*
X362993Y-645669D01*
X362593Y-644869D01*
X361993Y-644203D01*
X361193Y-643936D01*
G01X298418Y-624819D02*
Y-618519D01*
X301394D01*
G01X300298Y-621564D02*
X298418D01*
G01X306206Y-618519D02*
X305579Y-618729D01*
X305109Y-619254D01*
X304796Y-619884D01*
X304561Y-620724D01*
X304483Y-621669D01*
X304561Y-622614D01*
X304796Y-623454D01*
X305109Y-624084D01*
X305579Y-624609D01*
X306206Y-624819D01*
X306833Y-624609D01*
X307303Y-624084D01*
X307616Y-623454D01*
X307851Y-622614D01*
X307929Y-621669D01*
X307851Y-620724D01*
X307616Y-619884D01*
X307303Y-619254D01*
X306833Y-618729D01*
X306206Y-618519D01*
G01X312506D02*
Y-624819D01*
G01X310704Y-618519D02*
X314308D01*
G01X316456Y-626919D02*
X321156D01*
G01X323069Y-624819D02*
Y-618519D01*
X325106Y-623769D01*
X327143Y-618519D01*
Y-624819D01*
G01X332816D02*
Y-620619D01*
G01Y-621354D02*
X332503Y-620934D01*
X332033Y-620724D01*
X331484Y-620619D01*
X330936Y-620829D01*
X330466Y-621249D01*
X330153Y-621879D01*
X329996Y-622719D01*
X330153Y-623559D01*
X330466Y-624189D01*
X330936Y-624609D01*
X331484Y-624819D01*
X332033Y-624714D01*
X332503Y-624399D01*
X332816Y-623979D01*
G01X336374Y-624819D02*
Y-620619D01*
G01Y-621669D02*
X336688Y-621144D01*
X337158Y-620724D01*
X337784Y-620619D01*
X338333Y-620724D01*
X338803Y-621144D01*
X339038Y-621879D01*
Y-624819D01*
G01X345416D02*
Y-620619D01*
G01Y-621354D02*
X345103Y-620934D01*
X344633Y-620724D01*
X344084Y-620619D01*
X343536Y-620829D01*
X343066Y-621249D01*
X342753Y-621879D01*
X342596Y-622719D01*
X342753Y-623559D01*
X343066Y-624189D01*
X343536Y-624609D01*
X344084Y-624819D01*
X344633Y-624714D01*
X345103Y-624399D01*
X345416Y-623979D01*
G01X349209Y-626394D02*
X349758Y-626814D01*
X350384Y-626919D01*
X350933Y-626814D01*
X351403Y-626289D01*
X351716Y-625554D01*
Y-620619D01*
G01Y-621459D02*
X351403Y-621039D01*
X350933Y-620724D01*
X350384Y-620619D01*
X349758Y-620829D01*
X349366Y-621249D01*
X349053Y-621984D01*
X348896Y-622719D01*
X348974Y-623349D01*
X349288Y-624084D01*
X349758Y-624609D01*
X350384Y-624819D01*
X350854Y-624714D01*
X351403Y-624294D01*
X351716Y-623874D01*
G01X355431Y-621984D02*
X357938D01*
X357703Y-621249D01*
X357311Y-620829D01*
X356763Y-620619D01*
X356214Y-620724D01*
X355744Y-621039D01*
X355431Y-621774D01*
X355274Y-622404D01*
Y-623034D01*
X355431Y-623664D01*
X355823Y-624294D01*
X356293Y-624714D01*
X356841Y-624819D01*
X357389Y-624609D01*
X357938Y-623979D01*
G01X360556Y-624819D02*
Y-620619D01*
G01Y-621774D02*
X360791Y-621249D01*
X361183Y-620829D01*
X361731Y-620619D01*
X362279Y-620829D01*
X362671Y-621249D01*
X362906Y-621774D01*
Y-624819D01*
G01Y-621774D02*
X363141Y-621249D01*
X363533Y-620829D01*
X364081Y-620619D01*
X364629Y-620829D01*
X365021Y-621249D01*
X365256Y-621879D01*
Y-624819D01*
G01X368031Y-621984D02*
X370538D01*
X370303Y-621249D01*
X369911Y-620829D01*
X369363Y-620619D01*
X368814Y-620724D01*
X368344Y-621039D01*
X368031Y-621774D01*
X367874Y-622404D01*
Y-623034D01*
X368031Y-623664D01*
X368423Y-624294D01*
X368893Y-624714D01*
X369441Y-624819D01*
X369989Y-624609D01*
X370538Y-623979D01*
G01X374174Y-624819D02*
Y-620619D01*
G01Y-621669D02*
X374488Y-621144D01*
X374958Y-620724D01*
X375584Y-620619D01*
X376133Y-620724D01*
X376603Y-621144D01*
X376838Y-621879D01*
Y-624819D01*
G01X381806Y-618519D02*
Y-624819D01*
G01X380709Y-620619D02*
X382903D01*
G01X385756Y-626919D02*
X390456D01*
G01X395033Y-621459D02*
X395346Y-621144D01*
X395581Y-620619D01*
X395738Y-619884D01*
X395581Y-619254D01*
X395268Y-618834D01*
X394719Y-618519D01*
X392604D01*
Y-624819D01*
X395189D01*
X395738Y-624399D01*
X396051Y-623769D01*
X396208Y-623034D01*
X396051Y-622299D01*
X395581Y-621669D01*
X395033Y-621459D01*
X392604D01*
G01X398983Y-624819D02*
Y-618519D01*
X400549D01*
X401176Y-618834D01*
X401646Y-619254D01*
X402038Y-619884D01*
X402351Y-620619D01*
X402429Y-621669D01*
X402351Y-622719D01*
X402038Y-623454D01*
X401646Y-624084D01*
X401176Y-624504D01*
X400549Y-624819D01*
X398983D01*
G01X367693Y-679936D02*
Y-671936D01*
X366493Y-673536D01*
G01Y-679936D02*
X368893D01*
G01X373793Y-676603D02*
X374493Y-675669D01*
X375093Y-675136D01*
X375893Y-674869D01*
X376593Y-675136D01*
X377093Y-675669D01*
X377493Y-676469D01*
X377593Y-677403D01*
X377493Y-678203D01*
X377093Y-679003D01*
X376493Y-679669D01*
X375793Y-679936D01*
X374993Y-679669D01*
X374293Y-678870D01*
X373893Y-677669D01*
X373793Y-676336D01*
X373993Y-674603D01*
X374293Y-673669D01*
X374793Y-672736D01*
X375493Y-672069D01*
X376193Y-671936D01*
X376893Y-672203D01*
X377393Y-672869D01*
G01X383693Y-680203D02*
X383493Y-680069D01*
Y-679803D01*
X383693Y-679669D01*
X383893Y-679803D01*
Y-680069D01*
X383693Y-680203D01*
G01X389793Y-676603D02*
X390493Y-675669D01*
X391093Y-675136D01*
X391893Y-674869D01*
X392593Y-675136D01*
X393093Y-675669D01*
X393493Y-676469D01*
X393593Y-677403D01*
X393493Y-678203D01*
X393093Y-679003D01*
X392493Y-679669D01*
X391793Y-679936D01*
X390993Y-679669D01*
X390293Y-678870D01*
X389893Y-677669D01*
X389793Y-676336D01*
X389993Y-674603D01*
X390293Y-673669D01*
X390793Y-672736D01*
X391493Y-672069D01*
X392193Y-671936D01*
X392893Y-672203D01*
X393393Y-672869D01*
G01X412693Y-679936D02*
Y-671936D01*
X411493Y-673536D01*
G01Y-679936D02*
X413893D01*
G01X420493D02*
X420693Y-678203D01*
X420993Y-676736D01*
X421393Y-675403D01*
X421893Y-673936D01*
X422693Y-671936D01*
X418693D01*
G01X428693Y-680203D02*
X428493Y-680069D01*
Y-679803D01*
X428693Y-679669D01*
X428893Y-679803D01*
Y-680069D01*
X428693Y-680203D01*
G01X434793Y-673269D02*
X435393Y-672469D01*
X436093Y-672069D01*
X436893Y-671936D01*
X437893Y-672203D01*
X438593Y-672869D01*
X438793Y-673669D01*
X438693Y-674470D01*
X438293Y-675136D01*
X436293Y-676469D01*
X435393Y-677403D01*
X434793Y-678736D01*
X434593Y-679936D01*
X438793D01*
G01X432493Y-654936D02*
Y-646936D01*
X434493D01*
X435293Y-647336D01*
X435893Y-647869D01*
X436393Y-648669D01*
X436793Y-649603D01*
X436893Y-650936D01*
X436793Y-652269D01*
X436393Y-653203D01*
X435893Y-654003D01*
X435293Y-654536D01*
X434493Y-654936D01*
X432493D01*
M02*
